FILE_TYPE = MACRO_DRAWING;
SET COLOR_WIRE YELLOW;
SET COLOR_PROP ORANGE;
SET COLOR_DOT WHITE;
SET COLOR_ARC YELLOW;
SET COLOR_BODY GREEN;
SET COLOR_NOTE PURPLE;
SET PROP_DISPLAY VALUE;
SET PAGE_NUMBER P55;
SET PATH_NUMBER P72;
FORCEADD UNIVERSAL_GND..1
(-2125 975);
FORCEPROP 3 LASTPIN (-2125 1025) SIG_NAME GND\g
J 0
(-2115 1035);
DISPLAY 0.659574 (-2115 1035);
PAINT MONO (-2115 1035);
DISPLAY INVISIBLE (-2115 1035);
FORCEPROP 2 LAST CDS_LIB logical_power
J 0
(-2125 975);
DISPLAY INVISIBLE (-2125 975);
FORCEPROP 1 LAST HDL_POWER GND
J 1
(-2100 900);
DISPLAY 0.702128 (-2100 900);
PAINT GREEN (-2100 900);
DISPLAY INVISIBLE (-2100 900);
FORCEPROP 1 LAST PATH I10
J 0
(-2050 975);
DISPLAY 0.872340 (-2050 975);
PAINT AQUA (-2050 975);
DISPLAY INVISIBLE (-2050 975);
FORCEADD UNIVERSAL_GND..1
(-1225 -475);
FORCEPROP 3 LASTPIN (-1225 -425) SIG_NAME GND\g
J 0
(-1215 -415);
DISPLAY 0.659574 (-1215 -415);
PAINT MONO (-1215 -415);
DISPLAY INVISIBLE (-1215 -415);
FORCEPROP 2 LAST CDS_LIB logical_power
J 0
(-1225 -475);
DISPLAY INVISIBLE (-1225 -475);
FORCEPROP 1 LAST HDL_POWER GND
J 1
(-1200 -550);
DISPLAY 0.702128 (-1200 -550);
PAINT GREEN (-1200 -550);
DISPLAY INVISIBLE (-1200 -550);
FORCEPROP 1 LAST PATH I14
J 0
(-1150 -475);
DISPLAY 0.872340 (-1150 -475);
PAINT AQUA (-1150 -475);
DISPLAY INVISIBLE (-1150 -475);
FORCEADD NB695GDZ..1
(-175 400);
FORCEPROP 1 LAST MATERIAL IC
J 0
(-419 1157);
DISPLAY 0.510638 (-419 1157);
PAINT SKYBLUE (-419 1157);
FORCEPROP 1 LAST PART_NUMBER AL000695001
J 0
(-419 1284);
DISPLAY 0.510638 (-419 1284);
PAINT WHITE (-419 1284);
FORCEPROP 2 LAST PART_TYPE SMLF
J 0
(-425 1400);
DISPLAY 0.510638 (-425 1400);
PAINT SKYBLUE (-425 1400);
FORCEPROP 2 LAST VALUE NB695GD-Z
J 0
(-425 1350);
DISPLAY 0.510638 (-425 1350);
PAINT SKYBLUE (-425 1350);
FORCEPROP 2 LAST CDS_LIB pure_quanta
J 0
(-175 400);
DISPLAY INVISIBLE (-175 400);
FORCEPROP 1 LAST CDS_LMAN_SYM_OUTLINE -250,725,250,-725
J 0
(-175 400);
DISPLAY 0.468085 (-175 400);
PAINT GREEN (-175 400);
DISPLAY INVISIBLE (-175 400);
FORCEPROP 1 LAST NEEDS_NO_SIZE TRUE
J 0
(-175 400);
DISPLAY 0.723404 (-175 400);
PAINT GREEN (-175 400);
DISPLAY INVISIBLE (-175 400);
FORCEPROP 1 LAST PATH I15
J 0
(-175 400);
DISPLAY 0.723404 (-175 400);
PAINT GREEN (-175 400);
DISPLAY INVISIBLE (-175 400);
FORCEPROP 1 LAST LOCATION PU41
J 0
(-419 1431);
DISPLAY 0.702128 (-419 1431);
PAINT AQUA (-419 1431);
FORCEPROP 0 LASTPIN (-575 375) $PN 10
J 2
(-585 385);
DISPLAY 0.680851 (-585 385);
PAINT MONO (-585 385);
FORCEPROP 0 LASTPIN (225 -275) $PN 11
J 0
(235 -265);
DISPLAY 0.680851 (235 -265);
PAINT MONO (235 -265);
FORCEPROP 0 LASTPIN (225 875) $PN 9
J 0
(235 885);
DISPLAY 0.680851 (235 885);
PAINT MONO (235 885);
FORCEPROP 0 LASTPIN (-575 -125) $PN 4
J 2
(-585 -115);
DISPLAY 0.680851 (-585 -115);
PAINT MONO (-585 -115);
FORCEPROP 0 LASTPIN (-575 -25) $PN 3
J 2
(-585 -15);
DISPLAY 0.680851 (-585 -15);
PAINT MONO (-585 -15);
FORCEPROP 0 LASTPIN (-575 575) $PN 5
J 2
(-585 585);
DISPLAY 0.680851 (-585 585);
PAINT MONO (-585 585);
FORCEPROP 0 LASTPIN (-575 75) $PN 6
J 2
(-585 85);
DISPLAY 0.680851 (-585 85);
PAINT MONO (-585 85);
FORCEPROP 0 LASTPIN (-575 -275) $PN 7
J 2
(-585 -265);
DISPLAY 0.680851 (-585 -265);
PAINT MONO (-585 -265);
FORCEPROP 0 LASTPIN (225 1075) $PN 13
J 0
(235 1085);
DISPLAY 0.680851 (235 1085);
PAINT MONO (235 1085);
FORCEPROP 0 LASTPIN (225 -225) $PN 2
J 0
(235 -215);
DISPLAY 0.680851 (235 -215);
PAINT MONO (235 -215);
FORCEPROP 0 LASTPIN (225 575) $PN 8
J 0
(235 585);
DISPLAY 0.680851 (235 585);
PAINT MONO (235 585);
FORCEPROP 0 LASTPIN (-575 1075) $PN 1
J 2
(-585 1085);
DISPLAY 0.680851 (-585 1085);
PAINT MONO (-585 1085);
FORCEPROP 0 LASTPIN (225 -125) $PN 12
J 0
(235 -115);
DISPLAY 0.680851 (235 -115);
PAINT MONO (235 -115);
FORCEPROP 0 LAST $SEC 1
J 0
(-400 1475);
DISPLAY 0.680851 (-400 1475);
PAINT MONO (-400 1475);
DISPLAY INVISIBLE (-400 1475);
FORCEPROP 0 LAST CDS_SEC 1
J 0
(-400 1475);
DISPLAY 1.021277 (-400 1475);
DISPLAY INVISIBLE (-400 1475);
FORCEADD Q_CAP..1
(-1175 1300);
FORCEPROP 1 LAST MATERIAL X7R
J 0
(-1125 1200);
DISPLAY 0.510638 (-1125 1200);
PAINT SKYBLUE (-1125 1200);
FORCEPROP 1 LAST PART_NUMBER CH4104K1B00
J 0
(-1125 1150);
DISPLAY 0.510638 (-1125 1150);
PAINT WHITE (-1125 1150);
FORCEPROP 1 LAST TOLERANCE 10%
J 0
(-1125 1250);
DISPLAY 0.510638 (-1125 1250);
PAINT SKYBLUE (-1125 1250);
FORCEPROP 1 LAST VOLTAGE 25V
J 0
(-1125 1300);
DISPLAY 0.510638 (-1125 1300);
PAINT SKYBLUE (-1125 1300);
FORCEPROP 1 LAST PACK_TYPE 0402
J 0
(-1125 1100);
DISPLAY 0.510638 (-1125 1100);
PAINT SKYBLUE (-1125 1100);
FORCEPROP 1 LAST VALUE 0.1UF
J 0
(-1125 1350);
DISPLAY 0.510638 (-1125 1350);
PAINT SKYBLUE (-1125 1350);
FORCEPROP 2 LAST CDS_LIB pure_quanta
J 0
(-1175 1300);
DISPLAY INVISIBLE (-1175 1300);
FORCEPROP 2 LAST SEC_TYPE 0402
J 0
(-1125 1500);
DISPLAY 1.021277 (-1125 1500);
DISPLAY INVISIBLE (-1125 1500);
FORCEPROP 1 LAST PATH I16
J 0
(-1125 1450);
DISPLAY 0.978723 (-1125 1450);
PAINT WHITE (-1125 1450);
DISPLAY INVISIBLE (-1125 1450);
FORCEPROP 1 LAST LOCATION PC253
J 0
(-1125 1400);
DISPLAY 0.702128 (-1125 1400);
PAINT AQUA (-1125 1400);
FORCEPROP 1 LASTPIN (-1175 1400) $PN 1
J 0
(-1165 1380);
DISPLAY 0.808511 (-1165 1380);
PAINT WHITE (-1165 1380);
FORCEPROP 1 LASTPIN (-1175 1200) $PN 2
J 0
(-1165 1180);
DISPLAY 0.808511 (-1165 1180);
PAINT WHITE (-1165 1180);
FORCEPROP 2 LAST SEC 1
J 0
(-1125 1500);
DISPLAY 0.680851 (-1125 1500);
PAINT MONO (-1125 1500);
DISPLAY INVISIBLE (-1125 1500);
FORCEADD UNIVERSAL_GND..1
(375 -525);
FORCEPROP 3 LASTPIN (375 -475) SIG_NAME GND\g
J 0
(385 -465);
DISPLAY 0.659574 (385 -465);
PAINT MONO (385 -465);
DISPLAY INVISIBLE (385 -465);
FORCEPROP 2 LAST CDS_LIB logical_power
J 0
(375 -525);
DISPLAY INVISIBLE (375 -525);
FORCEPROP 1 LAST HDL_POWER GND
J 1
(400 -600);
DISPLAY 0.702128 (400 -600);
PAINT GREEN (400 -600);
DISPLAY INVISIBLE (400 -600);
FORCEPROP 1 LAST PATH I17
J 0
(450 -525);
DISPLAY 0.872340 (450 -525);
PAINT AQUA (450 -525);
DISPLAY INVISIBLE (450 -525);
FORCEADD Q_RES..2
(500 1350);
FORCEPROP 1 LAST TOLERANCE 1%
J 0
(545 1375);
DISPLAY 0.510638 (545 1375);
PAINT SKYBLUE (545 1375);
FORCEPROP 1 LAST WATTAGE 1/16W
J 0
(540 1325);
DISPLAY 0.510638 (540 1325);
PAINT SKYBLUE (540 1325);
FORCEPROP 1 LAST VALUE 10K
J 0
(545 1425);
DISPLAY 0.510638 (545 1425);
PAINT SKYBLUE (545 1425);
FORCEPROP 1 LAST PACK_TYPE 0402LF
J 0
(540 1175);
DISPLAY 0.510638 (540 1175);
PAINT SKYBLUE (540 1175);
FORCEPROP 1 LAST MATERIAL CHIP
J 0
(540 1275);
DISPLAY 0.510638 (540 1275);
PAINT SKYBLUE (540 1275);
FORCEPROP 1 LAST PART_NUMBER CS31002FB08
J 0
(540 1225);
DISPLAY 0.510638 (540 1225);
PAINT WHITE (540 1225);
FORCEPROP 2 LAST CDS_LIB pure_quanta
J 0
(500 1350);
DISPLAY INVISIBLE (500 1350);
FORCEPROP 2 LAST SEC_TYPE 0402LF
J 0
(550 1575);
DISPLAY 1.021277 (550 1575);
DISPLAY INVISIBLE (550 1575);
FORCEPROP 1 LAST PATH I18
J 0
(550 1525);
DISPLAY 0.978723 (550 1525);
PAINT WHITE (550 1525);
DISPLAY INVISIBLE (550 1525);
FORCEPROP 1 LAST LOCATION PR498
J 0
(545 1475);
DISPLAY 0.702128 (545 1475);
PAINT AQUA (545 1475);
FORCEPROP 1 LASTPIN (500 1450) $PN 1
J 0
(505 1412);
DISPLAY 0.808511 (505 1412);
PAINT WHITE (505 1412);
FORCEPROP 1 LASTPIN (500 1250) $PN 2
J 0
(505 1260);
DISPLAY 0.808511 (505 1260);
PAINT WHITE (505 1260);
FORCEPROP 2 LAST SEC 1
J 0
(550 1575);
DISPLAY 0.680851 (550 1575);
PAINT MONO (550 1575);
DISPLAY INVISIBLE (550 1575);
FORCEADD Q_CAP..1
(875 725);
FORCEPROP 1 LAST PACK_TYPE 0402
J 0
(950 600);
DISPLAY 0.510638 (950 600);
PAINT SKYBLUE (950 600);
FORCEPROP 1 LAST MATERIAL X7R
J 0
(950 700);
DISPLAY 0.510638 (950 700);
PAINT SKYBLUE (950 700);
FORCEPROP 1 LAST VALUE 0.22UF
J 0
(950 850);
DISPLAY 0.510638 (950 850);
PAINT SKYBLUE (950 850);
FORCEPROP 1 LAST VOLTAGE 16V
J 0
(950 800);
DISPLAY 0.510638 (950 800);
PAINT SKYBLUE (950 800);
FORCEPROP 1 LAST TOLERANCE 10%
J 0
(950 750);
DISPLAY 0.510638 (950 750);
PAINT SKYBLUE (950 750);
FORCEPROP 1 LAST PART_NUMBER CH4223K1B00
J 0
(950 650);
DISPLAY 0.510638 (950 650);
PAINT WHITE (950 650);
FORCEPROP 2 LAST SEC_TYPE 0402
J 0
(925 925);
DISPLAY 1.021277 (925 925);
DISPLAY INVISIBLE (925 925);
FORCEPROP 2 LAST CDS_LIB pure_quanta
J 0
(875 725);
DISPLAY INVISIBLE (875 725);
FORCEPROP 1 LAST PATH I19
J 0
(925 875);
DISPLAY 0.978723 (925 875);
PAINT WHITE (925 875);
DISPLAY INVISIBLE (925 875);
FORCEPROP 1 LAST LOCATION PC254
J 0
(950 900);
DISPLAY 0.702128 (950 900);
PAINT AQUA (950 900);
FORCEPROP 1 LASTPIN (875 825) $PN 1
J 0
(885 805);
DISPLAY 0.808511 (885 805);
PAINT WHITE (885 805);
FORCEPROP 1 LASTPIN (875 625) $PN 2
J 0
(885 605);
DISPLAY 0.808511 (885 605);
PAINT WHITE (885 605);
FORCEPROP 2 LAST SEC 1
J 0
(925 925);
DISPLAY 0.680851 (925 925);
PAINT MONO (925 925);
DISPLAY INVISIBLE (925 925);
FORCEADD VCCAUX15..1
(-3375 1900);
FORCEPROP 3 LASTPIN (-3375 1850) SIG_NAME P12V_AUX\g
J 0
(-3365 1860);
DISPLAY 0.659574 (-3365 1860);
PAINT MONO (-3365 1860);
DISPLAY INVISIBLE (-3365 1860);
FORCEPROP 1 LAST HDL_POWER P12V_AUX
J 1
(-3375 1950);
DISPLAY 0.702128 (-3375 1950);
PAINT GREEN (-3375 1950);
FORCEPROP 2 LAST CDS_LIB logical_power
J 0
(-3375 1900);
DISPLAY INVISIBLE (-3375 1900);
FORCEPROP 1 LAST PATH I2
J 0
(-3325 1925);
DISPLAY 0.872340 (-3325 1925);
PAINT AQUA (-3325 1925);
DISPLAY INVISIBLE (-3325 1925);
FORCEADD Q_INDUCTOR..1
(2125 600);
FORCEPROP 1 LAST MATERIAL IND
J 0
(2000 655);
DISPLAY 0.510638 (2000 655);
PAINT SKYBLUE (2000 655);
FORCEPROP 1 LAST PART_NUMBER CV-10B0MZ13
J 0
(2000 710);
DISPLAY 0.510638 (2000 710);
PAINT WHITE (2000 710);
FORCEPROP 2 LAST VALUE 1UH
J 0
(2050 500);
DISPLAY 0.510638 (2050 500);
PAINT SKYBLUE (2050 500);
FORCEPROP 2 LAST PACK_TYPE SMLF
J 0
(1825 500);
DISPLAY 0.510638 (1825 500);
PAINT SKYBLUE (1825 500);
FORCEPROP 0 LAST DCR DCR=9MOHM
J 0
(2050 425);
DISPLAY 0.510638 (2050 425);
PAINT WHITE (2050 425);
FORCEPROP 1 LAST NEEDS_NO_SIZE TRUE
J 0
(2125 600);
DISPLAY 0.468085 (2125 600);
PAINT GREEN (2125 600);
DISPLAY INVISIBLE (2125 600);
FORCEPROP 2 LAST CDS_LIB pure_quanta
J 0
(2125 600);
DISPLAY INVISIBLE (2125 600);
FORCEPROP 1 LAST PATH I21
J 0
(2200 655);
DISPLAY 0.723404 (2200 655);
PAINT GREEN (2200 655);
DISPLAY INVISIBLE (2200 655);
FORCEPROP 1 LAST LOCATION PL31
J 0
(2000 760);
DISPLAY 0.702128 (2000 760);
PAINT AQUA (2000 760);
FORCEPROP 0 LASTPIN (2025 575) $PN 1
J 2
(2015 585);
DISPLAY 0.808511 (2015 585);
PAINT WHITE (2015 585);
FORCEPROP 0 LASTPIN (2225 575) $PN 2
J 0
(2235 585);
DISPLAY 0.808511 (2235 585);
PAINT WHITE (2235 585);
FORCEPROP 0 LAST $SEC 1
J 0
(2000 800);
DISPLAY 0.680851 (2000 800);
PAINT MONO (2000 800);
DISPLAY INVISIBLE (2000 800);
FORCEPROP 0 LAST CDS_SEC 1
J 0
(2000 800);
DISPLAY 1.021277 (2000 800);
DISPLAY INVISIBLE (2000 800);
FORCEADD Q_CAP..1
(2625 325);
FORCEPROP 1 LAST MATERIAL X7R
J 0
(2675 225);
DISPLAY 0.510638 (2675 225);
PAINT SKYBLUE (2675 225);
FORCEPROP 1 LAST PART_NUMBER CH4104K1B00
J 0
(2675 175);
DISPLAY 0.510638 (2675 175);
PAINT WHITE (2675 175);
FORCEPROP 1 LAST VALUE 0.1UF
J 0
(2675 375);
DISPLAY 0.510638 (2675 375);
PAINT SKYBLUE (2675 375);
FORCEPROP 1 LAST TOLERANCE 10%
J 0
(2675 275);
DISPLAY 0.510638 (2675 275);
PAINT SKYBLUE (2675 275);
FORCEPROP 1 LAST VOLTAGE 25V
J 0
(2675 325);
DISPLAY 0.510638 (2675 325);
PAINT SKYBLUE (2675 325);
FORCEPROP 1 LAST PACK_TYPE 0402
J 0
(2675 125);
DISPLAY 0.510638 (2675 125);
PAINT SKYBLUE (2675 125);
FORCEPROP 2 LAST SEC_TYPE 0402
J 0
(2675 525);
DISPLAY 1.021277 (2675 525);
DISPLAY INVISIBLE (2675 525);
FORCEPROP 2 LAST CDS_LIB pure_quanta
J 0
(2625 325);
DISPLAY INVISIBLE (2625 325);
FORCEPROP 1 LAST PATH I23
J 0
(2675 475);
DISPLAY 0.978723 (2675 475);
PAINT WHITE (2675 475);
DISPLAY INVISIBLE (2675 475);
FORCEPROP 1 LAST LOCATION PC255
J 0
(2675 425);
DISPLAY 0.702128 (2675 425);
PAINT AQUA (2675 425);
FORCEPROP 1 LASTPIN (2625 425) $PN 1
J 0
(2635 405);
DISPLAY 0.808511 (2635 405);
PAINT WHITE (2635 405);
FORCEPROP 1 LASTPIN (2625 225) $PN 2
J 0
(2635 205);
DISPLAY 0.808511 (2635 205);
PAINT WHITE (2635 205);
FORCEPROP 2 LAST SEC 1
J 0
(2675 525);
DISPLAY 0.680851 (2675 525);
PAINT MONO (2675 525);
DISPLAY INVISIBLE (2675 525);
FORCEADD Q_CAP..1
(3175 325);
FORCEPROP 1 LAST VALUE 22UF
J 0
(3225 375);
DISPLAY 0.510638 (3225 375);
PAINT SKYBLUE (3225 375);
FORCEPROP 1 LAST PACK_TYPE 0805
J 0
(3225 125);
DISPLAY 0.510638 (3225 125);
PAINT SKYBLUE (3225 125);
FORCEPROP 1 LAST VOLTAGE 4V
J 0
(3225 325);
DISPLAY 0.510638 (3225 325);
PAINT SKYBLUE (3225 325);
FORCEPROP 1 LAST MATERIAL X6S
J 0
(3225 225);
DISPLAY 0.510638 (3225 225);
PAINT SKYBLUE (3225 225);
FORCEPROP 1 LAST TOLERANCE 20%
J 0
(3225 275);
DISPLAY 0.510638 (3225 275);
PAINT SKYBLUE (3225 275);
FORCEPROP 1 LAST PART_NUMBER TMP_QCH622KMEA01
J 0
(3225 175);
DISPLAY 0.510638 (3225 175);
PAINT WHITE (3225 175);
DISPLAY INVISIBLE (3225 175);
FORCEPROP 2 LAST CDS_LIB pure_quanta
J 0
(3175 325);
DISPLAY INVISIBLE (3175 325);
FORCEPROP 2 LAST SEC_TYPE 0805
J 0
(3225 525);
DISPLAY 1.021277 (3225 525);
DISPLAY INVISIBLE (3225 525);
FORCEPROP 1 LAST PATH I24
J 0
(3225 475);
DISPLAY 0.978723 (3225 475);
PAINT WHITE (3225 475);
DISPLAY INVISIBLE (3225 475);
FORCEPROP 1 LAST LOCATION PC256
J 0
(3225 425);
DISPLAY 0.702128 (3225 425);
PAINT AQUA (3225 425);
FORCEPROP 1 LASTPIN (3175 425) $PN 1
J 0
(3185 405);
DISPLAY 0.808511 (3185 405);
PAINT WHITE (3185 405);
FORCEPROP 1 LASTPIN (3175 225) $PN 2
J 0
(3185 205);
DISPLAY 0.808511 (3185 205);
PAINT WHITE (3185 205);
FORCEPROP 2 LAST SEC 1
J 0
(3225 525);
DISPLAY 0.680851 (3225 525);
PAINT MONO (3225 525);
DISPLAY INVISIBLE (3225 525);
FORCEADD Q_CAP..1
(3425 325);
FORCEPROP 1 LAST MATERIAL X6S
J 0
(3475 225);
DISPLAY 0.510638 (3475 225);
PAINT SKYBLUE (3475 225);
FORCEPROP 1 LAST VALUE 22UF
J 0
(3475 375);
DISPLAY 0.510638 (3475 375);
PAINT SKYBLUE (3475 375);
FORCEPROP 1 LAST TOLERANCE 20%
J 0
(3475 275);
DISPLAY 0.510638 (3475 275);
PAINT SKYBLUE (3475 275);
FORCEPROP 1 LAST VOLTAGE 4V
J 0
(3475 325);
DISPLAY 0.510638 (3475 325);
PAINT SKYBLUE (3475 325);
FORCEPROP 1 LAST PACK_TYPE 0805
J 0
(3475 125);
DISPLAY 0.510638 (3475 125);
PAINT SKYBLUE (3475 125);
FORCEPROP 1 LAST PART_NUMBER TMP_QCH622KMEA01
J 0
(3475 175);
DISPLAY 0.510638 (3475 175);
PAINT WHITE (3475 175);
DISPLAY INVISIBLE (3475 175);
FORCEPROP 2 LAST CDS_LIB pure_quanta
J 0
(3425 325);
DISPLAY INVISIBLE (3425 325);
FORCEPROP 2 LAST SEC_TYPE 0805
J 0
(3475 525);
DISPLAY 1.021277 (3475 525);
DISPLAY INVISIBLE (3475 525);
FORCEPROP 1 LAST PATH I25
J 0
(3475 475);
DISPLAY 0.978723 (3475 475);
PAINT WHITE (3475 475);
DISPLAY INVISIBLE (3475 475);
FORCEPROP 1 LAST LOCATION PC257
J 0
(3475 425);
DISPLAY 0.702128 (3475 425);
PAINT AQUA (3475 425);
FORCEPROP 1 LASTPIN (3425 425) $PN 1
J 0
(3435 405);
DISPLAY 0.808511 (3435 405);
PAINT WHITE (3435 405);
FORCEPROP 1 LASTPIN (3425 225) $PN 2
J 0
(3435 205);
DISPLAY 0.808511 (3435 205);
PAINT WHITE (3435 205);
FORCEPROP 2 LAST SEC 1
J 0
(3475 525);
DISPLAY 0.680851 (3475 525);
PAINT MONO (3475 525);
DISPLAY INVISIBLE (3475 525);
FORCEADD UNIVERSAL_GND..1
(3925 0);
FORCEPROP 3 LASTPIN (3925 50) SIG_NAME GND\g
J 0
(3935 60);
DISPLAY 0.659574 (3935 60);
PAINT MONO (3935 60);
DISPLAY INVISIBLE (3935 60);
FORCEPROP 2 LAST CDS_LIB logical_power
J 0
(3925 0);
DISPLAY INVISIBLE (3925 0);
FORCEPROP 1 LAST HDL_POWER GND
J 1
(3950 -75);
DISPLAY 0.702128 (3950 -75);
PAINT GREEN (3950 -75);
DISPLAY INVISIBLE (3950 -75);
FORCEPROP 1 LAST PATH I27
J 0
(4000 0);
DISPLAY 0.872340 (4000 0);
PAINT AQUA (4000 0);
DISPLAY INVISIBLE (4000 0);
FORCEADD Q_CAP..1
(3675 325);
FORCEPROP 1 LAST MATERIAL X6S
J 0
(3725 225);
DISPLAY 0.510638 (3725 225);
PAINT SKYBLUE (3725 225);
FORCEPROP 1 LAST VALUE 22UF
J 0
(3725 375);
DISPLAY 0.510638 (3725 375);
PAINT SKYBLUE (3725 375);
FORCEPROP 1 LAST TOLERANCE 20%
J 0
(3725 275);
DISPLAY 0.510638 (3725 275);
PAINT SKYBLUE (3725 275);
FORCEPROP 1 LAST PACK_TYPE 0805
J 0
(3725 125);
DISPLAY 0.510638 (3725 125);
PAINT SKYBLUE (3725 125);
FORCEPROP 1 LAST VOLTAGE 4V
J 0
(3725 325);
DISPLAY 0.510638 (3725 325);
PAINT SKYBLUE (3725 325);
FORCEPROP 1 LAST PART_NUMBER TMP_QCH622KMEA01
J 0
(3725 175);
DISPLAY 0.510638 (3725 175);
PAINT WHITE (3725 175);
DISPLAY INVISIBLE (3725 175);
FORCEPROP 2 LAST CDS_LIB pure_quanta
J 0
(3675 325);
DISPLAY INVISIBLE (3675 325);
FORCEPROP 2 LAST SEC_TYPE 0805
J 0
(3725 525);
DISPLAY 1.021277 (3725 525);
DISPLAY INVISIBLE (3725 525);
FORCEPROP 1 LAST PATH I28
J 0
(3725 475);
DISPLAY 0.978723 (3725 475);
PAINT WHITE (3725 475);
DISPLAY INVISIBLE (3725 475);
FORCEPROP 1 LAST LOCATION PC258
J 0
(3725 425);
DISPLAY 0.702128 (3725 425);
PAINT AQUA (3725 425);
FORCEPROP 1 LASTPIN (3675 425) $PN 1
J 0
(3685 405);
DISPLAY 0.808511 (3685 405);
PAINT WHITE (3685 405);
FORCEPROP 1 LASTPIN (3675 225) $PN 2
J 0
(3685 205);
DISPLAY 0.808511 (3685 205);
PAINT WHITE (3685 205);
FORCEPROP 2 LAST SEC 1
J 0
(3725 525);
DISPLAY 0.680851 (3725 525);
PAINT MONO (3725 525);
DISPLAY INVISIBLE (3725 525);
FORCEADD Q_CAP..1
(3925 325);
FORCEPROP 1 LAST PART_NUMBER TMP_QCH622KMEA01
J 0
(3975 175);
DISPLAY 0.510638 (3975 175);
PAINT WHITE (3975 175);
FORCEPROP 1 LAST PACK_TYPE 0805
J 0
(3975 125);
DISPLAY 0.510638 (3975 125);
PAINT SKYBLUE (3975 125);
FORCEPROP 1 LAST MATERIAL X6S
J 0
(3975 225);
DISPLAY 0.510638 (3975 225);
PAINT SKYBLUE (3975 225);
FORCEPROP 1 LAST VALUE 22UF
J 0
(3975 375);
DISPLAY 0.510638 (3975 375);
PAINT SKYBLUE (3975 375);
FORCEPROP 1 LAST TOLERANCE 20%
J 0
(3975 275);
DISPLAY 0.510638 (3975 275);
PAINT SKYBLUE (3975 275);
FORCEPROP 1 LAST VOLTAGE 4V
J 0
(3975 325);
DISPLAY 0.510638 (3975 325);
PAINT SKYBLUE (3975 325);
FORCEPROP 2 LAST CDS_LIB pure_quanta
J 0
(3925 325);
DISPLAY INVISIBLE (3925 325);
FORCEPROP 2 LAST SEC_TYPE 0805
J 0
(3975 525);
DISPLAY 1.021277 (3975 525);
DISPLAY INVISIBLE (3975 525);
FORCEPROP 1 LAST PATH I29
J 0
(3975 475);
DISPLAY 0.978723 (3975 475);
PAINT WHITE (3975 475);
DISPLAY INVISIBLE (3975 475);
FORCEPROP 1 LAST LOCATION PC259
J 0
(3975 425);
DISPLAY 0.702128 (3975 425);
PAINT AQUA (3975 425);
FORCEPROP 1 LASTPIN (3925 425) $PN 1
J 0
(3935 405);
DISPLAY 0.808511 (3935 405);
PAINT WHITE (3935 405);
FORCEPROP 1 LASTPIN (3925 225) $PN 2
J 0
(3935 205);
DISPLAY 0.808511 (3935 205);
PAINT WHITE (3935 205);
FORCEPROP 2 LAST SEC 1
J 0
(3975 525);
DISPLAY 0.680851 (3975 525);
PAINT MONO (3975 525);
DISPLAY INVISIBLE (3975 525);
FORCEADD VCCAUX15..1
(4575 700);
FORCEPROP 3 LASTPIN (4575 650) SIG_NAME P1V2_AUX\g
J 0
(4585 660);
DISPLAY 0.659574 (4585 660);
PAINT MONO (4585 660);
DISPLAY INVISIBLE (4585 660);
FORCEPROP 1 LAST HDL_POWER P1V2_AUX
J 1
(4575 750);
DISPLAY 0.702128 (4575 750);
PAINT GREEN (4575 750);
FORCEPROP 2 LAST CDS_LIB logical_power
J 0
(4575 700);
DISPLAY INVISIBLE (4575 700);
FORCEPROP 1 LAST PATH I30
J 0
(4625 725);
DISPLAY 0.872340 (4625 725);
PAINT AQUA (4625 725);
DISPLAY INVISIBLE (4625 725);
FORCEADD Q_INDUCTOR..1
(-2775 1575);
FORCEPROP 1 LAST MATERIAL IND
J 0
(-2875 1450);
DISPLAY 0.510638 (-2875 1450);
PAINT SKYBLUE (-2875 1450);
FORCEPROP 2 LAST PACK_TYPE SMLF
J 0
(-2850 1325);
DISPLAY 0.510638 (-2850 1325);
PAINT SKYBLUE (-2850 1325);
FORCEPROP 1 LAST PART_NUMBER CX220TN1001
J 0
(-2975 1500);
DISPLAY 0.510638 (-2975 1500);
PAINT WHITE (-2975 1500);
FORCEPROP 2 LAST VALUE BLM18SN220TN1D/8000MA
J 0
(-3125 1400);
DISPLAY 0.510638 (-3125 1400);
PAINT SKYBLUE (-3125 1400);
FORCEPROP 1 LAST PATH I31
J 0
(-2700 1630);
DISPLAY 0.723404 (-2700 1630);
PAINT GREEN (-2700 1630);
DISPLAY INVISIBLE (-2700 1630);
FORCEPROP 1 LAST NEEDS_NO_SIZE TRUE
J 0
(-2775 1575);
DISPLAY 0.468085 (-2775 1575);
PAINT GREEN (-2775 1575);
DISPLAY INVISIBLE (-2775 1575);
FORCEPROP 2 LAST CDS_LIB pure_quanta
J 0
(-2775 1575);
DISPLAY INVISIBLE (-2775 1575);
FORCEPROP 1 LAST LOCATION PL29
J 0
(-2875 1625);
DISPLAY 0.702128 (-2875 1625);
PAINT AQUA (-2875 1625);
FORCEPROP 0 LASTPIN (-2875 1550) $PN 1
J 2
(-2885 1560);
DISPLAY 0.808511 (-2885 1560);
PAINT WHITE (-2885 1560);
FORCEPROP 0 LASTPIN (-2675 1550) $PN 2
J 0
(-2665 1560);
DISPLAY 0.808511 (-2665 1560);
PAINT WHITE (-2665 1560);
FORCEPROP 0 LAST $SEC 1
J 0
(-2875 1675);
DISPLAY 0.680851 (-2875 1675);
PAINT MONO (-2875 1675);
DISPLAY INVISIBLE (-2875 1675);
FORCEPROP 0 LAST CDS_SEC 1
J 0
(-2875 1675);
DISPLAY 1.021277 (-2875 1675);
DISPLAY INVISIBLE (-2875 1675);
FORCEADD VCCAUX15..1
(500 1625);
FORCEPROP 3 LASTPIN (500 1575) SIG_NAME P3V3_AUX\g
J 0
(510 1585);
DISPLAY 0.659574 (510 1585);
PAINT MONO (510 1585);
DISPLAY INVISIBLE (510 1585);
FORCEPROP 1 LAST HDL_POWER P3V3_AUX
J 1
(500 1675);
DISPLAY 0.702128 (500 1675);
PAINT GREEN (500 1675);
FORCEPROP 2 LAST CDS_LIB logical_power
J 0
(500 1625);
DISPLAY INVISIBLE (500 1625);
FORCEPROP 1 LAST PATH I34
J 0
(550 1650);
DISPLAY 0.872340 (550 1650);
PAINT AQUA (550 1650);
DISPLAY INVISIBLE (550 1650);
FORCEADD OFFPAGE..5
R 2
(3025 1075);
FORCEPROP 2 LAST $XR1 56 
J 0
(3304 1075);
DISPLAY 0.638298 (3304 1075);
PAINT MONO (3304 1075);
FORCEPROP 2 LAST $XR0 36 
J 0
(3214 1075);
DISPLAY 0.638298 (3214 1075);
PAINT MONO (3214 1075);
FORCEPROP 1 LAST COMMENT_BODY TRUE
J 2
(2925 1000);
DISPLAY 0.872340 (2925 1000);
PAINT PEACH (2925 1000);
DISPLAY INVISIBLE (2925 1000);
FORCEPROP 1 LAST OFFPAGE TRUE
J 2
(2700 950);
DISPLAY 0.872340 (2700 950);
PAINT GREEN (2700 950);
DISPLAY INVISIBLE (2700 950);
FORCEPROP 2 LAST CDS_LIB standard
J 0
(3025 1075);
DISPLAY INVISIBLE (3025 1075);
FORCEPROP 2 LAST PATH I35
J 0
(3075 1150);
DISPLAY 1.021277 (3075 1150);
DISPLAY INVISIBLE (3075 1150);
FORCEADD Q_RES..1
(-1700 675);
FORCEPROP 1 LAST MATERIAL CHIP
J 0
(-1450 675);
DISPLAY 0.510638 (-1450 675);
PAINT SKYBLUE (-1450 675);
FORCEPROP 1 LAST VALUE 0
J 2
(-1475 675);
DISPLAY 0.510638 (-1475 675);
PAINT SKYBLUE (-1475 675);
FORCEPROP 1 LAST PART_NUMBER CS00002JB13
J 0
(-1800 725);
DISPLAY 0.510638 (-1800 725);
PAINT WHITE (-1800 725);
FORCEPROP 1 LAST PACK_TYPE 0402LF
J 0
(-1450 525);
DISPLAY 0.510638 (-1450 525);
PAINT SKYBLUE (-1450 525);
DISPLAY INVISIBLE (-1450 525);
FORCEPROP 1 LAST WATTAGE 1/16W
J 2
(-1725 525);
DISPLAY 0.510638 (-1725 525);
PAINT SKYBLUE (-1725 525);
DISPLAY INVISIBLE (-1725 525);
FORCEPROP 1 LAST TOLERANCE 5%
J 0
(-1700 575);
DISPLAY 0.510638 (-1700 575);
PAINT SKYBLUE (-1700 575);
DISPLAY INVISIBLE (-1700 575);
FORCEPROP 1 LAST PATH I38
J 0
(-1750 825);
DISPLAY 0.978723 (-1750 825);
PAINT WHITE (-1750 825);
DISPLAY INVISIBLE (-1750 825);
FORCEPROP 2 LAST CDS_LIB pure_quanta
J 0
(-1700 675);
DISPLAY INVISIBLE (-1700 675);
FORCEPROP 1 LAST LOCATION R708
J 0
(-1950 675);
DISPLAY 0.702128 (-1950 675);
PAINT YELLOW (-1950 675);
FORCEPROP 1 LASTPIN (-1800 675) $PN 1
J 0
(-1788 687);
DISPLAY 0.808511 (-1788 687);
PAINT WHITE (-1788 687);
FORCEPROP 1 LASTPIN (-1600 675) $PN 2
J 0
(-1638 687);
DISPLAY 0.808511 (-1638 687);
PAINT WHITE (-1638 687);
FORCEPROP 2 LAST $SEC 1
J 0
(-1825 900);
DISPLAY 0.680851 (-1825 900);
PAINT MONO (-1825 900);
DISPLAY INVISIBLE (-1825 900);
FORCEPROP 0 LAST CDS_SEC 1
J 0
(-1825 900);
DISPLAY 0.680851 (-1825 900);
PAINT MONO (-1825 900);
DISPLAY INVISIBLE (-1825 900);
FORCEADD OFFPAGE..4
R 2
(-2675 675);
FORCEPROP 2 LAST $XR0 55 
J 0
(-2896 675);
DISPLAY 0.638298 (-2896 675);
PAINT MONO (-2896 675);
FORCEPROP 2 LAST CDS_LIB standard
J 0
(-2675 675);
DISPLAY INVISIBLE (-2675 675);
FORCEPROP 1 LAST OFFPAGE TRUE
J 2
(-3000 550);
DISPLAY 0.872340 (-3000 550);
PAINT GREEN (-3000 550);
DISPLAY INVISIBLE (-3000 550);
FORCEPROP 1 LAST COMMENT_BODY TRUE
J 2
(-2650 575);
DISPLAY 0.872340 (-2650 575);
PAINT PEACH (-2650 575);
DISPLAY INVISIBLE (-2650 575);
FORCEPROP 2 LAST PATH I39
J 0
(-2625 750);
DISPLAY 1.021277 (-2625 750);
DISPLAY INVISIBLE (-2625 750);
FORCEADD UNIVERSAL_GND..1
(-3575 -525);
FORCEPROP 3 LASTPIN (-3575 -475) SIG_NAME GND\g
J 0
(-3565 -465);
DISPLAY 0.659574 (-3565 -465);
PAINT MONO (-3565 -465);
DISPLAY INVISIBLE (-3565 -465);
FORCEPROP 2 LAST CDS_LIB logical_power
J 0
(-3575 -525);
DISPLAY INVISIBLE (-3575 -525);
FORCEPROP 1 LAST HDL_POWER GND
J 1
(-3550 -600);
DISPLAY 0.702128 (-3550 -600);
PAINT GREEN (-3550 -600);
DISPLAY INVISIBLE (-3550 -600);
FORCEPROP 1 LAST PATH I4
J 0
(-3500 -525);
DISPLAY 0.872340 (-3500 -525);
PAINT AQUA (-3500 -525);
DISPLAY INVISIBLE (-3500 -525);
FORCEADD OFFPAGE..4
R 2
(-2675 575);
FORCEPROP 2 LAST $XR2 52 
J 0
(-3076 575);
DISPLAY 0.638298 (-3076 575);
PAINT MONO (-3076 575);
FORCEPROP 2 LAST $XR1 36 
J 0
(-2986 575);
DISPLAY 0.638298 (-2986 575);
PAINT MONO (-2986 575);
FORCEPROP 2 LAST $XR0 54 
J 0
(-2896 575);
DISPLAY 0.638298 (-2896 575);
PAINT MONO (-2896 575);
FORCEPROP 1 LAST COMMENT_BODY TRUE
J 2
(-2650 475);
DISPLAY 0.872340 (-2650 475);
PAINT PEACH (-2650 475);
DISPLAY INVISIBLE (-2650 475);
FORCEPROP 1 LAST OFFPAGE TRUE
J 2
(-3000 450);
DISPLAY 0.872340 (-3000 450);
PAINT GREEN (-3000 450);
DISPLAY INVISIBLE (-3000 450);
FORCEPROP 2 LAST CDS_LIB standard
J 0
(-2675 575);
DISPLAY INVISIBLE (-2675 575);
FORCEPROP 2 LAST PATH I40
J 0
(-2875 625);
DISPLAY 1.021277 (-2875 625);
DISPLAY INVISIBLE (-2875 625);
FORCEADD Q_RES..1
(-1700 575);
FORCEPROP 1 LAST MATERIAL EMPTY
J 0
(-1450 575);
DISPLAY 0.510638 (-1450 575);
PAINT RED (-1450 575);
FORCEPROP 1 LAST VALUE 0
J 2
(-1475 575);
DISPLAY 0.510638 (-1475 575);
PAINT SKYBLUE (-1475 575);
FORCEPROP 1 LAST PART_NUMBER CS00002JB13
J 0
(-1800 625);
DISPLAY 0.510638 (-1800 625);
PAINT WHITE (-1800 625);
DISPLAY INVISIBLE (-1800 625);
FORCEPROP 1 LAST PACK_TYPE 0402LF
J 0
(-1450 425);
DISPLAY 0.510638 (-1450 425);
PAINT SKYBLUE (-1450 425);
DISPLAY INVISIBLE (-1450 425);
FORCEPROP 1 LAST WATTAGE 1/16W
J 2
(-1725 425);
DISPLAY 0.510638 (-1725 425);
PAINT SKYBLUE (-1725 425);
DISPLAY INVISIBLE (-1725 425);
FORCEPROP 1 LAST TOLERANCE 5%
J 0
(-1700 475);
DISPLAY 0.510638 (-1700 475);
PAINT SKYBLUE (-1700 475);
DISPLAY INVISIBLE (-1700 475);
FORCEPROP 1 LAST PATH I41
J 0
(-1750 725);
DISPLAY 0.978723 (-1750 725);
PAINT WHITE (-1750 725);
DISPLAY INVISIBLE (-1750 725);
FORCEPROP 2 LAST CDS_LIB pure_quanta
J 0
(-1700 575);
DISPLAY INVISIBLE (-1700 575);
FORCEPROP 1 LAST LOCATION R764
J 0
(-1950 575);
DISPLAY 0.702128 (-1950 575);
PAINT YELLOW (-1950 575);
FORCEPROP 1 LASTPIN (-1800 575) $PN 1
J 0
(-1788 587);
DISPLAY 0.808511 (-1788 587);
PAINT WHITE (-1788 587);
FORCEPROP 1 LASTPIN (-1600 575) $PN 2
J 0
(-1638 587);
DISPLAY 0.808511 (-1638 587);
PAINT WHITE (-1638 587);
FORCEPROP 2 LAST $SEC 1
J 0
(-1825 800);
DISPLAY 0.680851 (-1825 800);
PAINT MONO (-1825 800);
DISPLAY INVISIBLE (-1825 800);
FORCEPROP 0 LAST CDS_SEC 1
J 0
(-1825 800);
DISPLAY 0.680851 (-1825 800);
PAINT MONO (-1825 800);
DISPLAY INVISIBLE (-1825 800);
FORCEADD Q_CAP..1
(-2125 1300);
FORCEPROP 1 LAST PACK_TYPE C0805
J 0
(-2075 1100);
DISPLAY 0.510638 (-2075 1100);
PAINT SKYBLUE (-2075 1100);
FORCEPROP 1 LAST VALUE 10UF
J 0
(-2075 1350);
DISPLAY 0.510638 (-2075 1350);
PAINT SKYBLUE (-2075 1350);
FORCEPROP 1 LAST TOLERANCE 10%
J 0
(-2075 1250);
DISPLAY 0.510638 (-2075 1250);
PAINT SKYBLUE (-2075 1250);
FORCEPROP 1 LAST PART_NUMBER CH6104KEA00
J 0
(-2075 1150);
DISPLAY 0.510638 (-2075 1150);
PAINT WHITE (-2075 1150);
FORCEPROP 1 LAST MATERIAL X6S
J 0
(-2075 1200);
DISPLAY 0.510638 (-2075 1200);
PAINT SKYBLUE (-2075 1200);
FORCEPROP 1 LAST VOLTAGE 25V
J 0
(-2075 1300);
DISPLAY 0.510638 (-2075 1300);
PAINT SKYBLUE (-2075 1300);
FORCEPROP 2 LAST CDS_LIB pure_quanta
J 0
(-2125 1300);
DISPLAY INVISIBLE (-2125 1300);
FORCEPROP 1 LAST PATH I42
J 0
(-2075 1450);
DISPLAY 0.978723 (-2075 1450);
PAINT WHITE (-2075 1450);
DISPLAY INVISIBLE (-2075 1450);
FORCEPROP 1 LAST LOCATION PC252
J 0
(-2075 1400);
DISPLAY 0.702128 (-2075 1400);
PAINT AQUA (-2075 1400);
FORCEPROP 0 LAST $SEC 1
J 0
(-2075 1450);
DISPLAY 0.680851 (-2075 1450);
PAINT MONO (-2075 1450);
DISPLAY INVISIBLE (-2075 1450);
FORCEPROP 0 LAST CDS_SEC 1
J 0
(-2075 1450);
DISPLAY 1.021277 (-2075 1450);
DISPLAY INVISIBLE (-2075 1450);
FORCEPROP 1 LASTPIN (-2125 1400) $PN 1
J 0
(-2115 1380);
DISPLAY 0.808511 (-2115 1380);
PAINT WHITE (-2115 1380);
DISPLAY INVISIBLE (-2115 1380);
FORCEPROP 1 LASTPIN (-2125 1200) $PN 2
J 0
(-2115 1180);
DISPLAY 0.808511 (-2115 1180);
PAINT WHITE (-2115 1180);
DISPLAY INVISIBLE (-2115 1180);
FORCEADD Q_CAP..1
(-1725 1300);
FORCEPROP 1 LAST PART_NUMBER CH6104KEA00
J 0
(-1675 1150);
DISPLAY 0.510638 (-1675 1150);
PAINT WHITE (-1675 1150);
FORCEPROP 1 LAST TOLERANCE 10%
J 0
(-1675 1250);
DISPLAY 0.510638 (-1675 1250);
PAINT SKYBLUE (-1675 1250);
FORCEPROP 1 LAST VOLTAGE 25V
J 0
(-1675 1300);
DISPLAY 0.510638 (-1675 1300);
PAINT SKYBLUE (-1675 1300);
FORCEPROP 1 LAST PACK_TYPE C0805
J 0
(-1675 1100);
DISPLAY 0.510638 (-1675 1100);
PAINT SKYBLUE (-1675 1100);
FORCEPROP 1 LAST MATERIAL X6S
J 0
(-1675 1200);
DISPLAY 0.510638 (-1675 1200);
PAINT SKYBLUE (-1675 1200);
FORCEPROP 1 LAST VALUE 10UF
J 0
(-1675 1350);
DISPLAY 0.510638 (-1675 1350);
PAINT SKYBLUE (-1675 1350);
FORCEPROP 2 LAST CDS_LIB pure_quanta
J 0
(-1725 1300);
DISPLAY INVISIBLE (-1725 1300);
FORCEPROP 1 LAST PATH I43
J 0
(-1675 1450);
DISPLAY 0.978723 (-1675 1450);
PAINT WHITE (-1675 1450);
DISPLAY INVISIBLE (-1675 1450);
FORCEPROP 1 LAST LOCATION PC251
J 0
(-1675 1400);
DISPLAY 0.702128 (-1675 1400);
PAINT AQUA (-1675 1400);
FORCEPROP 0 LAST $SEC 1
J 0
(-1675 1450);
DISPLAY 0.680851 (-1675 1450);
PAINT MONO (-1675 1450);
DISPLAY INVISIBLE (-1675 1450);
FORCEPROP 0 LAST CDS_SEC 1
J 0
(-1675 1450);
DISPLAY 1.021277 (-1675 1450);
DISPLAY INVISIBLE (-1675 1450);
FORCEPROP 1 LASTPIN (-1725 1400) $PN 1
J 0
(-1715 1380);
DISPLAY 0.808511 (-1715 1380);
PAINT WHITE (-1715 1380);
DISPLAY INVISIBLE (-1715 1380);
FORCEPROP 1 LASTPIN (-1725 1200) $PN 2
J 0
(-1715 1180);
DISPLAY 0.808511 (-1715 1180);
PAINT WHITE (-1715 1180);
DISPLAY INVISIBLE (-1715 1180);
FORCEADD VCCAUX15..1
(-1900 -1100);
FORCEPROP 3 LASTPIN (-1900 -1150) SIG_NAME P3V3_AUX\g
J 0
(-1890 -1140);
DISPLAY 0.659574 (-1890 -1140);
PAINT MONO (-1890 -1140);
DISPLAY INVISIBLE (-1890 -1140);
FORCEPROP 1 LAST HDL_POWER P3V3_AUX
J 1
(-1900 -1050);
DISPLAY 0.702128 (-1900 -1050);
PAINT GREEN (-1900 -1050);
FORCEPROP 2 LAST CDS_LIB logical_power
J 0
(-1900 -1100);
DISPLAY INVISIBLE (-1900 -1100);
FORCEPROP 1 LAST PATH I44
J 0
(-1850 -1075);
DISPLAY 0.872340 (-1850 -1075);
PAINT AQUA (-1850 -1075);
DISPLAY INVISIBLE (-1850 -1075);
FORCEADD Q_RES..1
(-1350 -1225);
FORCEPROP 1 LAST TOLERANCE 5%
J 0
(-1350 -1325);
DISPLAY 0.510638 (-1350 -1325);
PAINT SKYBLUE (-1350 -1325);
FORCEPROP 1 LAST MATERIAL CHIP
J 0
(-1350 -1375);
DISPLAY 0.510638 (-1350 -1375);
PAINT SKYBLUE (-1350 -1375);
FORCEPROP 1 LAST VALUE 0
J 2
(-1375 -1325);
DISPLAY 0.510638 (-1375 -1325);
PAINT SKYBLUE (-1375 -1325);
FORCEPROP 1 LAST WATTAGE 1/16W
J 2
(-1375 -1375);
DISPLAY 0.510638 (-1375 -1375);
PAINT SKYBLUE (-1375 -1375);
FORCEPROP 1 LAST PACK_TYPE 0402LF
J 0
(-1200 -1375);
DISPLAY 0.510638 (-1200 -1375);
PAINT SKYBLUE (-1200 -1375);
FORCEPROP 1 LAST PART_NUMBER CS00002JB13
J 0
(-1250 -1200);
DISPLAY 0.510638 (-1250 -1200);
PAINT WHITE (-1250 -1200);
FORCEPROP 2 LAST CDS_LIB pure_quanta
J 0
(-1350 -1225);
DISPLAY INVISIBLE (-1350 -1225);
FORCEPROP 1 LAST PATH I45
J 0
(-1400 -1075);
DISPLAY 0.978723 (-1400 -1075);
PAINT WHITE (-1400 -1075);
DISPLAY INVISIBLE (-1400 -1075);
FORCEPROP 1 LAST LOCATION PR274
J 0
(-1625 -1200);
DISPLAY 0.702128 (-1625 -1200);
PAINT AQUA (-1625 -1200);
FORCEPROP 0 LAST $SEC 1
J 0
(-1625 -1150);
DISPLAY 0.680851 (-1625 -1150);
PAINT MONO (-1625 -1150);
DISPLAY INVISIBLE (-1625 -1150);
FORCEPROP 0 LAST CDS_SEC 1
J 0
(-1625 -1150);
DISPLAY 1.021277 (-1625 -1150);
DISPLAY INVISIBLE (-1625 -1150);
FORCEPROP 1 LASTPIN (-1450 -1225) $PN 1
J 0
(-1438 -1213);
DISPLAY 0.808511 (-1438 -1213);
PAINT WHITE (-1438 -1213);
DISPLAY INVISIBLE (-1438 -1213);
FORCEPROP 1 LASTPIN (-1250 -1225) $PN 2
J 0
(-1288 -1213);
DISPLAY 0.808511 (-1288 -1213);
PAINT WHITE (-1288 -1213);
DISPLAY INVISIBLE (-1288 -1213);
FORCEADD VCCAUX15..1
(-625 -1075);
FORCEPROP 3 LASTPIN (-625 -1125) SIG_NAME PVCC1_AUX\g
J 0
(-615 -1115);
DISPLAY 0.659574 (-615 -1115);
PAINT MONO (-615 -1115);
DISPLAY INVISIBLE (-615 -1115);
FORCEPROP 1 LAST HDL_POWER PVCC1_AUX
J 1
(-625 -1025);
DISPLAY 0.702128 (-625 -1025);
PAINT GREEN (-625 -1025);
FORCEPROP 2 LAST CDS_LIB logical_power
J 0
(-625 -1075);
DISPLAY INVISIBLE (-625 -1075);
FORCEPROP 1 LAST PATH I46
J 0
(-575 -1050);
DISPLAY 0.872340 (-575 -1050);
PAINT AQUA (-575 -1050);
DISPLAY INVISIBLE (-575 -1050);
FORCEADD VCCAUX15..1
(-1900 -1450);
FORCEPROP 3 LASTPIN (-1900 -1500) SIG_NAME P5V_AUX\g
J 0
(-1890 -1490);
DISPLAY 0.659574 (-1890 -1490);
PAINT MONO (-1890 -1490);
DISPLAY INVISIBLE (-1890 -1490);
FORCEPROP 1 LAST HDL_POWER P5V_AUX
J 1
(-1900 -1400);
DISPLAY 0.702128 (-1900 -1400);
PAINT GREEN (-1900 -1400);
FORCEPROP 2 LAST CDS_LIB logical_power
J 0
(-1900 -1450);
DISPLAY INVISIBLE (-1900 -1450);
FORCEPROP 1 LAST PATH I47
J 0
(-1850 -1425);
DISPLAY 0.872340 (-1850 -1425);
PAINT AQUA (-1850 -1425);
DISPLAY INVISIBLE (-1850 -1425);
FORCEADD Q_RES..1
(-1350 -1550);
FORCEPROP 1 LAST PART_NUMBER CS00002JB13
J 0
(-1250 -1525);
DISPLAY 0.510638 (-1250 -1525);
PAINT WHITE (-1250 -1525);
FORCEPROP 1 LAST VALUE 0
J 2
(-1375 -1650);
DISPLAY 0.510638 (-1375 -1650);
PAINT SKYBLUE (-1375 -1650);
FORCEPROP 1 LAST TOLERANCE 5%
J 0
(-1350 -1650);
DISPLAY 0.510638 (-1350 -1650);
PAINT SKYBLUE (-1350 -1650);
FORCEPROP 1 LAST MATERIAL EMPTY
J 0
(-1350 -1700);
DISPLAY 0.510638 (-1350 -1700);
PAINT RED (-1350 -1700);
FORCEPROP 1 LAST WATTAGE 1/16W
J 2
(-1375 -1700);
DISPLAY 0.510638 (-1375 -1700);
PAINT SKYBLUE (-1375 -1700);
FORCEPROP 1 LAST PACK_TYPE 0402LF
J 0
(-1200 -1700);
DISPLAY 0.510638 (-1200 -1700);
PAINT SKYBLUE (-1200 -1700);
FORCEPROP 2 LAST CDS_LIB pure_quanta
J 0
(-1350 -1550);
DISPLAY INVISIBLE (-1350 -1550);
FORCEPROP 1 LAST PATH I48
J 0
(-1400 -1400);
DISPLAY 0.978723 (-1400 -1400);
PAINT WHITE (-1400 -1400);
DISPLAY INVISIBLE (-1400 -1400);
FORCEPROP 1 LAST LOCATION PR275
J 0
(-1625 -1525);
DISPLAY 0.702128 (-1625 -1525);
PAINT AQUA (-1625 -1525);
FORCEPROP 0 LAST $SEC 1
J 0
(-1625 -1475);
DISPLAY 0.680851 (-1625 -1475);
PAINT MONO (-1625 -1475);
DISPLAY INVISIBLE (-1625 -1475);
FORCEPROP 0 LAST CDS_SEC 1
J 0
(-1625 -1475);
DISPLAY 1.021277 (-1625 -1475);
DISPLAY INVISIBLE (-1625 -1475);
FORCEPROP 1 LASTPIN (-1450 -1550) $PN 1
J 0
(-1438 -1538);
DISPLAY 0.808511 (-1438 -1538);
PAINT WHITE (-1438 -1538);
DISPLAY INVISIBLE (-1438 -1538);
FORCEPROP 1 LASTPIN (-1250 -1550) $PN 2
J 0
(-1288 -1538);
DISPLAY 0.808511 (-1288 -1538);
PAINT WHITE (-1288 -1538);
DISPLAY INVISIBLE (-1288 -1538);
FORCEADD VCCAUX15..1
(-625 -1400);
FORCEPROP 3 LASTPIN (-625 -1450) SIG_NAME PVCC1_AUX\g
J 0
(-615 -1440);
DISPLAY 0.659574 (-615 -1440);
PAINT MONO (-615 -1440);
DISPLAY INVISIBLE (-615 -1440);
FORCEPROP 1 LAST HDL_POWER PVCC1_AUX
J 1
(-625 -1350);
DISPLAY 0.702128 (-625 -1350);
PAINT GREEN (-625 -1350);
FORCEPROP 2 LAST CDS_LIB logical_power
J 0
(-625 -1400);
DISPLAY INVISIBLE (-625 -1400);
FORCEPROP 1 LAST PATH I49
J 0
(-575 -1375);
DISPLAY 0.872340 (-575 -1375);
PAINT AQUA (-575 -1375);
DISPLAY INVISIBLE (-575 -1375);
FORCEADD UNIVERSAL_GND..1
(-1050 -850);
FORCEPROP 3 LASTPIN (-1050 -800) SIG_NAME GND\g
J 0
(-1040 -790);
DISPLAY 0.659574 (-1040 -790);
PAINT MONO (-1040 -790);
DISPLAY INVISIBLE (-1040 -790);
FORCEPROP 2 LAST CDS_LIB logical_power
J 0
(-1050 -850);
DISPLAY INVISIBLE (-1050 -850);
FORCEPROP 1 LAST HDL_POWER GND
J 1
(-1025 -925);
DISPLAY 0.702128 (-1025 -925);
PAINT GREEN (-1025 -925);
DISPLAY INVISIBLE (-1025 -925);
FORCEPROP 1 LAST PATH I5
J 0
(-975 -850);
DISPLAY 0.872340 (-975 -850);
PAINT AQUA (-975 -850);
DISPLAY INVISIBLE (-975 -850);
FORCEADD Q_RES..1
(1750 1075);
FORCEPROP 1 LAST PACK_TYPE 0402LF
J 0
(1675 1025);
DISPLAY 0.510638 (1675 1025);
PAINT SKYBLUE (1675 1025);
FORCEPROP 1 LAST VALUE 0
J 2
(1975 1075);
DISPLAY 0.510638 (1975 1075);
PAINT SKYBLUE (1975 1075);
FORCEPROP 1 LAST PART_NUMBER CS00002JB13
J 0
(1650 1125);
DISPLAY 0.510638 (1650 1125);
PAINT WHITE (1650 1125);
FORCEPROP 1 LAST MATERIAL CHIP
J 0
(2000 1075);
DISPLAY 0.510638 (2000 1075);
PAINT SKYBLUE (2000 1075);
FORCEPROP 1 LAST WATTAGE 1/16W
J 2
(1725 925);
DISPLAY 0.510638 (1725 925);
PAINT SKYBLUE (1725 925);
DISPLAY INVISIBLE (1725 925);
FORCEPROP 1 LAST TOLERANCE 5%
J 0
(1750 975);
DISPLAY 0.510638 (1750 975);
PAINT SKYBLUE (1750 975);
DISPLAY INVISIBLE (1750 975);
FORCEPROP 1 LAST PATH I50
J 0
(1700 1225);
DISPLAY 0.978723 (1700 1225);
PAINT WHITE (1700 1225);
DISPLAY INVISIBLE (1700 1225);
FORCEPROP 2 LAST CDS_LIB pure_quanta
J 0
(1750 1075);
DISPLAY INVISIBLE (1750 1075);
FORCEPROP 1 LAST LOCATION R276
J 0
(1500 1075);
DISPLAY 0.702128 (1500 1075);
PAINT YELLOW (1500 1075);
FORCEPROP 1 LASTPIN (1650 1075) $PN 1
J 0
(1662 1087);
DISPLAY 0.808511 (1662 1087);
PAINT WHITE (1662 1087);
FORCEPROP 1 LASTPIN (1850 1075) $PN 2
J 0
(1812 1087);
DISPLAY 0.808511 (1812 1087);
PAINT WHITE (1812 1087);
FORCEPROP 2 LAST $SEC 1
J 0
(1625 1300);
DISPLAY 0.680851 (1625 1300);
PAINT MONO (1625 1300);
DISPLAY INVISIBLE (1625 1300);
FORCEPROP 0 LAST CDS_SEC 1
J 0
(1625 1300);
DISPLAY 0.680851 (1625 1300);
PAINT MONO (1625 1300);
DISPLAY INVISIBLE (1625 1300);
FORCEADD UNIVERSAL_GND..1
(1325 675);
FORCEPROP 3 LASTPIN (1325 725) SIG_NAME GND\g
J 0
(1335 735);
DISPLAY 0.659574 (1335 735);
PAINT MONO (1335 735);
DISPLAY INVISIBLE (1335 735);
FORCEPROP 2 LAST CDS_LIB logical_power
J 0
(1325 675);
DISPLAY INVISIBLE (1325 675);
FORCEPROP 1 LAST HDL_POWER GND
J 1
(1350 600);
DISPLAY 0.702128 (1350 600);
PAINT GREEN (1350 600);
DISPLAY INVISIBLE (1350 600);
FORCEPROP 1 LAST PATH I51
J 0
(1400 675);
DISPLAY 0.872340 (1400 675);
PAINT AQUA (1400 675);
DISPLAY INVISIBLE (1400 675);
FORCEADD Q_CAP..1
(1325 875);
FORCEPROP 1 LAST PACK_TYPE C0402
J 0
(1375 675);
DISPLAY 0.787234 (1375 675);
FORCEPROP 1 LAST PART_NUMBER CH30106KB19
J 0
(1375 725);
DISPLAY 0.787234 (1375 725);
FORCEPROP 1 LAST VALUE 0.001UF
J 0
(1375 925);
DISPLAY 0.787234 (1375 925);
FORCEPROP 1 LAST VOLTAGE 50V
J 0
(1375 875);
DISPLAY 0.787234 (1375 875);
FORCEPROP 1 LAST TOLERANCE 10%
J 0
(1375 825);
DISPLAY 0.787234 (1375 825);
FORCEPROP 1 LAST MATERIAL EMPTY
J 0
(1375 775);
DISPLAY 0.787234 (1375 775);
FORCEPROP 1 LAST PATH I52
J 0
(1375 1025);
DISPLAY 0.978723 (1375 1025);
PAINT WHITE (1375 1025);
DISPLAY INVISIBLE (1375 1025);
FORCEPROP 2 LAST CDS_LIB pure_quanta
J 0
(1325 875);
DISPLAY INVISIBLE (1325 875);
FORCEPROP 1 LAST LOCATION C155
J 0
(1375 975);
DISPLAY 0.787234 (1375 975);
FORCEPROP 1 LASTPIN (1325 975) $PN 1
J 0
(1335 955);
DISPLAY 0.787234 (1335 955);
PAINT MONO (1335 955);
FORCEPROP 1 LASTPIN (1325 775) $PN 2
J 0
(1335 755);
DISPLAY 0.787234 (1335 755);
PAINT MONO (1335 755);
FORCEPROP 0 LAST $SEC 1
J 0
(1375 1025);
DISPLAY 0.680851 (1375 1025);
PAINT MONO (1375 1025);
DISPLAY INVISIBLE (1375 1025);
FORCEPROP 0 LAST CDS_SEC 1
J 0
(1375 1025);
DISPLAY 0.680851 (1375 1025);
DISPLAY INVISIBLE (1375 1025);
FORCEADD UNIVERSAL_GND..1
(-3375 1175);
FORCEPROP 3 LASTPIN (-3375 1225) SIG_NAME GND\g
J 0
(-3365 1235);
DISPLAY 0.659574 (-3365 1235);
PAINT MONO (-3365 1235);
DISPLAY INVISIBLE (-3365 1235);
FORCEPROP 1 LAST HDL_POWER GND
J 1
(-3350 1100);
DISPLAY 0.702128 (-3350 1100);
PAINT GREEN (-3350 1100);
DISPLAY INVISIBLE (-3350 1100);
FORCEPROP 1 LAST PATH I53
J 0
(-3300 1175);
DISPLAY 0.872340 (-3300 1175);
PAINT AQUA (-3300 1175);
DISPLAY INVISIBLE (-3300 1175);
FORCEPROP 2 LAST CDS_LIB logical_power
J 0
(-3375 1175);
DISPLAY INVISIBLE (-3375 1175);
FORCEADD Q_CAP..1
(-3375 1375);
FORCEPROP 1 LAST TOLERANCE 10%
J 0
(-3325 1325);
DISPLAY 0.510638 (-3325 1325);
PAINT SKYBLUE (-3325 1325);
FORCEPROP 1 LAST MATERIAL X7R
J 0
(-3325 1275);
DISPLAY 0.510638 (-3325 1275);
PAINT SKYBLUE (-3325 1275);
FORCEPROP 1 LAST VALUE 0.1UF
J 0
(-3325 1425);
DISPLAY 0.510638 (-3325 1425);
PAINT SKYBLUE (-3325 1425);
FORCEPROP 1 LAST VOLTAGE 25V
J 0
(-3325 1375);
DISPLAY 0.510638 (-3325 1375);
PAINT SKYBLUE (-3325 1375);
FORCEPROP 1 LAST PACK_TYPE 0402
J 0
(-3325 1175);
DISPLAY 0.510638 (-3325 1175);
PAINT SKYBLUE (-3325 1175);
FORCEPROP 1 LAST PART_NUMBER CH4104K1B00
J 0
(-3325 1225);
DISPLAY 0.510638 (-3325 1225);
PAINT WHITE (-3325 1225);
FORCEPROP 1 LAST PATH I54
J 0
(-3325 1525);
DISPLAY 0.978723 (-3325 1525);
PAINT WHITE (-3325 1525);
DISPLAY INVISIBLE (-3325 1525);
FORCEPROP 2 LAST CDS_LIB pure_quanta
J 0
(-3375 1375);
DISPLAY INVISIBLE (-3375 1375);
FORCEPROP 1 LAST $LOCATION C278
J 0
(-3325 1475);
DISPLAY 0.978723 (-3325 1475);
FORCEPROP 1 LASTPIN (-3375 1475) $PN 1
J 0
(-3365 1455);
DISPLAY 0.787234 (-3365 1455);
PAINT MONO (-3365 1455);
FORCEPROP 1 LASTPIN (-3375 1275) $PN 2
J 0
(-3365 1255);
DISPLAY 0.787234 (-3365 1255);
PAINT MONO (-3365 1255);
FORCEPROP 0 LAST CDS_LOCATION C278
J 0
(-3325 1525);
DISPLAY 0.680851 (-3325 1525);
DISPLAY INVISIBLE (-3325 1525);
FORCEPROP 0 LAST $SEC 1
J 0
(-3325 1525);
DISPLAY 0.680851 (-3325 1525);
PAINT MONO (-3325 1525);
DISPLAY INVISIBLE (-3325 1525);
FORCEPROP 0 LAST CDS_SEC 1
J 0
(-3325 1525);
DISPLAY 0.680851 (-3325 1525);
DISPLAY INVISIBLE (-3325 1525);
FORCEADD OFFPAGE..4
R 2
(-2900 3000);
FORCEPROP 2 LAST $XR4 56 
J 0
(-3481 3000);
DISPLAY 0.638298 (-3481 3000);
PAINT MONO (-3481 3000);
FORCEPROP 2 LAST $XR3 54 
J 0
(-3391 3000);
DISPLAY 0.638298 (-3391 3000);
PAINT MONO (-3391 3000);
FORCEPROP 2 LAST $XR2 52 
J 0
(-3301 3000);
DISPLAY 0.638298 (-3301 3000);
PAINT MONO (-3301 3000);
FORCEPROP 2 LAST $XR1 35 
J 0
(-3211 3000);
DISPLAY 0.638298 (-3211 3000);
PAINT MONO (-3211 3000);
FORCEPROP 2 LAST $XR0 51 
J 0
(-3121 3000);
DISPLAY 0.638298 (-3121 3000);
PAINT MONO (-3121 3000);
FORCEPROP 2 LAST PATH I55
J 0
(-3150 3050);
DISPLAY 0.680851 (-3150 3050);
DISPLAY INVISIBLE (-3150 3050);
FORCEPROP 1 LAST COMMENT_BODY TRUE
J 2
(-2875 2900);
DISPLAY 0.872340 (-2875 2900);
PAINT PEACH (-2875 2900);
DISPLAY INVISIBLE (-2875 2900);
FORCEPROP 1 LAST OFFPAGE TRUE
J 2
(-3225 2875);
DISPLAY 0.872340 (-3225 2875);
PAINT GREEN (-3225 2875);
DISPLAY INVISIBLE (-3225 2875);
FORCEPROP 2 LAST CDS_LIB standard
J 0
(-2900 3000);
DISPLAY INVISIBLE (-2900 3000);
FORCEADD OFFPAGE..4
R 2
(-2900 2900);
FORCEPROP 2 LAST $XR0 52 
J 0
(-3121 2900);
DISPLAY 0.638298 (-3121 2900);
PAINT MONO (-3121 2900);
FORCEPROP 2 LAST $XR1 36 
J 0
(-3211 2900);
DISPLAY 0.638298 (-3211 2900);
PAINT MONO (-3211 2900);
FORCEPROP 2 LAST $XR2 54 
J 0
(-3301 2900);
DISPLAY 0.638298 (-3301 2900);
PAINT MONO (-3301 2900);
FORCEPROP 2 LAST PATH I56
J 0
(-3150 2950);
DISPLAY 0.680851 (-3150 2950);
DISPLAY INVISIBLE (-3150 2950);
FORCEPROP 1 LAST COMMENT_BODY TRUE
J 2
(-2875 2800);
DISPLAY 0.872340 (-2875 2800);
PAINT PEACH (-2875 2800);
DISPLAY INVISIBLE (-2875 2800);
FORCEPROP 1 LAST OFFPAGE TRUE
J 2
(-3225 2775);
DISPLAY 0.872340 (-3225 2775);
PAINT GREEN (-3225 2775);
DISPLAY INVISIBLE (-3225 2775);
FORCEPROP 2 LAST CDS_LIB standard
J 0
(-2900 2900);
DISPLAY INVISIBLE (-2900 2900);
FORCEADD UNIVERSAL_GND..1
(-2050 2525);
FORCEPROP 3 LASTPIN (-2050 2575) SIG_NAME GND\g
J 0
(-2040 2585);
DISPLAY 0.659574 (-2040 2585);
PAINT MONO (-2040 2585);
DISPLAY INVISIBLE (-2040 2585);
FORCEPROP 1 LAST PATH I57
J 0
(-1975 2525);
DISPLAY 0.872340 (-1975 2525);
PAINT AQUA (-1975 2525);
DISPLAY INVISIBLE (-1975 2525);
FORCEPROP 1 LAST HDL_POWER GND
J 1
(-2025 2450);
DISPLAY 0.702128 (-2025 2450);
PAINT GREEN (-2025 2450);
DISPLAY INVISIBLE (-2025 2450);
FORCEPROP 2 LAST CDS_LIB logical_power
J 0
(-2050 2525);
DISPLAY INVISIBLE (-2050 2525);
FORCEADD Q_RES..2
(-1050 -600);
FORCEPROP 1 LAST VALUE 150K
J 0
(-1005 -525);
DISPLAY 0.510638 (-1005 -525);
PAINT SKYBLUE (-1005 -525);
FORCEPROP 1 LAST TOLERANCE 1%
J 0
(-1005 -575);
DISPLAY 0.510638 (-1005 -575);
PAINT SKYBLUE (-1005 -575);
FORCEPROP 1 LAST WATTAGE 1/16W
J 0
(-1010 -625);
DISPLAY 0.510638 (-1010 -625);
PAINT SKYBLUE (-1010 -625);
FORCEPROP 1 LAST MATERIAL CHIP
J 0
(-1010 -675);
DISPLAY 0.510638 (-1010 -675);
PAINT SKYBLUE (-1010 -675);
FORCEPROP 1 LAST PACK_TYPE 0402LF
J 0
(-1010 -775);
DISPLAY 0.510638 (-1010 -775);
PAINT SKYBLUE (-1010 -775);
FORCEPROP 1 LAST PART_NUMBER CS41502FB04
J 0
(-1010 -725);
DISPLAY 0.510638 (-1010 -725);
PAINT WHITE (-1010 -725);
FORCEPROP 2 LAST SEC_TYPE 0402LF
J 0
(-1000 -375);
DISPLAY 1.021277 (-1000 -375);
DISPLAY INVISIBLE (-1000 -375);
FORCEPROP 2 LAST CDS_LIB pure_quanta
J 0
(-1050 -600);
DISPLAY INVISIBLE (-1050 -600);
FORCEPROP 1 LAST PATH I6
J 0
(-1000 -425);
DISPLAY 0.978723 (-1000 -425);
PAINT WHITE (-1000 -425);
DISPLAY INVISIBLE (-1000 -425);
FORCEPROP 1 LAST LOCATION PR496
J 0
(-1005 -475);
DISPLAY 0.702128 (-1005 -475);
PAINT AQUA (-1005 -475);
FORCEPROP 1 LASTPIN (-1050 -500) $PN 1
J 0
(-1045 -538);
DISPLAY 0.808511 (-1045 -538);
PAINT WHITE (-1045 -538);
FORCEPROP 1 LASTPIN (-1050 -700) $PN 2
J 0
(-1045 -690);
DISPLAY 0.808511 (-1045 -690);
PAINT WHITE (-1045 -690);
FORCEPROP 2 LAST SEC 1
J 0
(-1000 -375);
DISPLAY 0.680851 (-1000 -375);
PAINT MONO (-1000 -375);
DISPLAY INVISIBLE (-1000 -375);
FORCEADD UNIVERSAL_GND..1
(-1700 3225);
FORCEPROP 3 LASTPIN (-1700 3275) SIG_NAME GND\g
J 0
(-1690 3285);
DISPLAY 0.659574 (-1690 3285);
PAINT MONO (-1690 3285);
DISPLAY INVISIBLE (-1690 3285);
FORCEPROP 1 LAST HDL_POWER GND
J 1
(-1675 3150);
DISPLAY 0.702128 (-1675 3150);
PAINT GREEN (-1675 3150);
DISPLAY INVISIBLE (-1675 3150);
FORCEPROP 2 LAST CDS_LIB logical_power
J 0
(-1700 3225);
DISPLAY INVISIBLE (-1700 3225);
FORCEPROP 1 LAST PATH I60
J 0
(-1625 3225);
DISPLAY 0.872340 (-1625 3225);
PAINT AQUA (-1625 3225);
DISPLAY INVISIBLE (-1625 3225);
FORCEADD Q_CAP..1
R 2
(-1700 3425);
FORCEPROP 1 LAST PACK_TYPE 0402
J 2
(-1750 3250);
DISPLAY 0.510638 (-1750 3250);
PAINT SKYBLUE (-1750 3250);
FORCEPROP 1 LAST MATERIAL X7R
J 2
(-1750 3300);
DISPLAY 0.510638 (-1750 3300);
PAINT SKYBLUE (-1750 3300);
FORCEPROP 1 LAST TOLERANCE 10%
J 2
(-1750 3350);
DISPLAY 0.510638 (-1750 3350);
PAINT SKYBLUE (-1750 3350);
FORCEPROP 1 LAST VOLTAGE 25V
J 2
(-1750 3400);
DISPLAY 0.510638 (-1750 3400);
PAINT SKYBLUE (-1750 3400);
FORCEPROP 1 LAST VALUE 0.1UF
J 2
(-1750 3450);
DISPLAY 0.510638 (-1750 3450);
PAINT SKYBLUE (-1750 3450);
FORCEPROP 1 LAST PART_NUMBER CH4104K1B00
J 2
(-1750 3200);
DISPLAY 0.510638 (-1750 3200);
PAINT WHITE (-1750 3200);
FORCEPROP 1 LAST PATH I61
J 2
(-1750 3575);
DISPLAY 0.978723 (-1750 3575);
PAINT WHITE (-1750 3575);
DISPLAY INVISIBLE (-1750 3575);
FORCEPROP 2 LAST CDS_LIB pure_quanta
J 0
(-1700 3425);
DISPLAY INVISIBLE (-1700 3425);
FORCEPROP 1 LAST $LOCATION C301
J 2
(-1750 3525);
DISPLAY 0.978723 (-1750 3525);
FORCEPROP 1 LASTPIN (-1700 3525) $PN 1
J 2
(-1710 3505);
DISPLAY 0.787234 (-1710 3505);
PAINT MONO (-1710 3505);
FORCEPROP 1 LASTPIN (-1700 3325) $PN 2
J 2
(-1710 3305);
DISPLAY 0.787234 (-1710 3305);
PAINT MONO (-1710 3305);
FORCEPROP 0 LAST CDS_LOCATION C301
J 0
(-1750 3575);
DISPLAY 0.680851 (-1750 3575);
DISPLAY INVISIBLE (-1750 3575);
FORCEPROP 0 LAST $SEC 1
J 0
(-1750 3575);
DISPLAY 0.680851 (-1750 3575);
PAINT MONO (-1750 3575);
DISPLAY INVISIBLE (-1750 3575);
FORCEPROP 0 LAST CDS_SEC 1
J 0
(-1750 3575);
DISPLAY 0.680851 (-1750 3575);
DISPLAY INVISIBLE (-1750 3575);
FORCEADD 74LVC1G08GW..1
(-2000 2950);
FORCEPROP 1 LAST MATERIAL IC
J 0
(-1850 2760);
DISPLAY 0.723404 (-1850 2760);
PAINT GREEN (-1850 2760);
FORCEPROP 2 LAST PACK_TYPE SM
J 0
(-1850 2900);
DISPLAY 0.680851 (-1850 2900);
FORCEPROP 2 LAST VALUE 74LVC1G08GW
J 0
(-1950 3075);
DISPLAY 0.680851 (-1950 3075);
FORCEPROP 1 LAST PART_NUMBER ALVC1G08009
J 0
(-1850 2810);
DISPLAY 0.723404 (-1850 2810);
PAINT GREEN (-1850 2810);
FORCEPROP 1 LAST PATH I63
J 0
(-1725 2755);
DISPLAY 0.723404 (-1725 2755);
PAINT GREEN (-1725 2755);
DISPLAY INVISIBLE (-1725 2755);
FORCEPROP 2 LAST CDS_LIB pure_quanta
J 0
(-2000 2950);
DISPLAY INVISIBLE (-2000 2950);
FORCEPROP 1 LAST NEEDS_NO_SIZE TRUE
J 0
(-2000 2950);
DISPLAY 0.468085 (-2000 2950);
PAINT GREEN (-2000 2950);
DISPLAY INVISIBLE (-2000 2950);
FORCEPROP 1 LAST $LOCATION U52
J 0
(-1850 2855);
DISPLAY 0.723404 (-1850 2855);
PAINT GREEN (-1850 2855);
FORCEPROP 0 LASTPIN (-2300 2900) $PN 2
J 2
(-2310 2910);
DISPLAY 0.680851 (-2310 2910);
PAINT MONO (-2310 2910);
FORCEPROP 0 LASTPIN (-2300 3000) $PN 1
J 2
(-2310 3010);
DISPLAY 0.680851 (-2310 3010);
PAINT MONO (-2310 3010);
FORCEPROP 0 LASTPIN (-2050 2700) $PN 3
R 1
J 2
(-2060 2690);
DISPLAY 0.680851 (-2060 2690);
PAINT MONO (-2060 2690);
FORCEPROP 0 LASTPIN (-2050 3200) $PN 5
R 1
J 0
(-2060 3210);
DISPLAY 0.680851 (-2060 3210);
PAINT MONO (-2060 3210);
FORCEPROP 0 LASTPIN (-1700 2950) $PN 4
J 0
(-1690 2960);
DISPLAY 0.680851 (-1690 2960);
PAINT MONO (-1690 2960);
FORCEPROP 0 LAST CDS_LOCATION U52
J 0
(-1950 3125);
DISPLAY 0.680851 (-1950 3125);
DISPLAY INVISIBLE (-1950 3125);
FORCEPROP 0 LAST $SEC 1
J 0
(-1950 3125);
DISPLAY 0.680851 (-1950 3125);
PAINT MONO (-1950 3125);
DISPLAY INVISIBLE (-1950 3125);
FORCEPROP 0 LAST CDS_SEC 1
J 0
(-1950 3125);
DISPLAY 0.680851 (-1950 3125);
DISPLAY INVISIBLE (-1950 3125);
FORCEADD OFFPAGE..5
R 2
(-775 2950);
FORCEPROP 2 LAST $XR0 55 
J 0
(-586 2950);
DISPLAY 0.638298 (-586 2950);
PAINT MONO (-586 2950);
FORCEPROP 1 LAST COMMENT_BODY TRUE
J 2
(-875 2875);
DISPLAY 0.872340 (-875 2875);
PAINT PEACH (-875 2875);
DISPLAY INVISIBLE (-875 2875);
FORCEPROP 1 LAST OFFPAGE TRUE
J 2
(-1100 2825);
DISPLAY 0.872340 (-1100 2825);
PAINT GREEN (-1100 2825);
DISPLAY INVISIBLE (-1100 2825);
FORCEPROP 2 LAST CDS_LIB standard
J 0
(-775 2950);
DISPLAY INVISIBLE (-775 2950);
FORCEPROP 2 LAST PATH I67
J 0
(-575 3000);
DISPLAY 0.680851 (-575 3000);
DISPLAY INVISIBLE (-575 3000);
FORCEADD Q_RES..1
(-1700 475);
FORCEPROP 1 LAST VALUE 0
J 2
(-1475 475);
DISPLAY 0.510638 (-1475 475);
PAINT SKYBLUE (-1475 475);
FORCEPROP 1 LAST MATERIAL EMPTY
J 0
(-1450 475);
DISPLAY 0.510638 (-1450 475);
PAINT RED (-1450 475);
FORCEPROP 1 LAST TOLERANCE 5%
J 0
(-1700 375);
DISPLAY 0.510638 (-1700 375);
PAINT SKYBLUE (-1700 375);
DISPLAY INVISIBLE (-1700 375);
FORCEPROP 1 LAST WATTAGE 1/16W
J 2
(-1725 325);
DISPLAY 0.510638 (-1725 325);
PAINT SKYBLUE (-1725 325);
DISPLAY INVISIBLE (-1725 325);
FORCEPROP 1 LAST PACK_TYPE 0402LF
J 0
(-1450 325);
DISPLAY 0.510638 (-1450 325);
PAINT SKYBLUE (-1450 325);
DISPLAY INVISIBLE (-1450 325);
FORCEPROP 1 LAST PART_NUMBER CS00002JB13
J 0
(-1800 525);
DISPLAY 0.510638 (-1800 525);
PAINT WHITE (-1800 525);
DISPLAY INVISIBLE (-1800 525);
FORCEPROP 1 LAST PATH I68
J 0
(-1750 625);
DISPLAY 0.978723 (-1750 625);
PAINT WHITE (-1750 625);
DISPLAY INVISIBLE (-1750 625);
FORCEPROP 2 LAST CDS_LIB pure_quanta
J 0
(-1700 475);
DISPLAY INVISIBLE (-1700 475);
FORCEPROP 1 LAST $LOCATION R876
J 0
(-1950 475);
DISPLAY 0.702128 (-1950 475);
PAINT YELLOW (-1950 475);
FORCEPROP 1 LASTPIN (-1800 475) $PN 1
J 0
(-1788 487);
DISPLAY 0.787234 (-1788 487);
PAINT MONO (-1788 487);
FORCEPROP 1 LASTPIN (-1600 475) $PN 2
J 0
(-1638 487);
DISPLAY 0.787234 (-1638 487);
PAINT MONO (-1638 487);
FORCEPROP 0 LAST CDS_LOCATION R876
J 0
(-1950 525);
DISPLAY 0.680851 (-1950 525);
DISPLAY INVISIBLE (-1950 525);
FORCEPROP 0 LAST $SEC 1
J 0
(-1950 525);
DISPLAY 0.680851 (-1950 525);
PAINT MONO (-1950 525);
DISPLAY INVISIBLE (-1950 525);
FORCEPROP 0 LAST CDS_SEC 1
J 0
(-1950 525);
DISPLAY 0.680851 (-1950 525);
DISPLAY INVISIBLE (-1950 525);
FORCEADD OFFPAGE..4
R 2
(-2675 475);
FORCEPROP 2 LAST $XR0 52 
J 0
(-2896 475);
DISPLAY 0.638298 (-2896 475);
PAINT MONO (-2896 475);
FORCEPROP 2 LAST PATH I69
J 0
(-2875 525);
DISPLAY 0.680851 (-2875 525);
DISPLAY INVISIBLE (-2875 525);
FORCEPROP 1 LAST COMMENT_BODY TRUE
J 2
(-2650 375);
DISPLAY 0.872340 (-2650 375);
PAINT PEACH (-2650 375);
DISPLAY INVISIBLE (-2650 375);
FORCEPROP 1 LAST OFFPAGE TRUE
J 2
(-3000 350);
DISPLAY 0.872340 (-3000 350);
PAINT GREEN (-3000 350);
DISPLAY INVISIBLE (-3000 350);
FORCEPROP 2 LAST CDS_LIB standard
J 0
(-2675 475);
DISPLAY INVISIBLE (-2675 475);
FORCEADD Q_CAP..1
(-3575 -225);
FORCEPROP 1 LAST VOLTAGE 25V
J 0
(-3525 -225);
DISPLAY 0.510638 (-3525 -225);
PAINT SKYBLUE (-3525 -225);
FORCEPROP 1 LAST PACK_TYPE C0402
J 0
(-3525 -425);
DISPLAY 0.510638 (-3525 -425);
PAINT SKYBLUE (-3525 -425);
FORCEPROP 1 LAST TOLERANCE 10%
J 0
(-3525 -275);
DISPLAY 0.510638 (-3525 -275);
PAINT SKYBLUE (-3525 -275);
FORCEPROP 1 LAST VALUE 1UF
J 0
(-3525 -175);
DISPLAY 0.510638 (-3525 -175);
PAINT SKYBLUE (-3525 -175);
FORCEPROP 1 LAST PART_NUMBER CH5104KEB02
J 0
(-3525 -375);
DISPLAY 0.510638 (-3525 -375);
PAINT WHITE (-3525 -375);
FORCEPROP 1 LAST MATERIAL X6S
J 0
(-3525 -325);
DISPLAY 0.510638 (-3525 -325);
PAINT SKYBLUE (-3525 -325);
FORCEPROP 2 LAST CDS_LIB pure_quanta
J 0
(-3575 -225);
DISPLAY INVISIBLE (-3575 -225);
FORCEPROP 2 LAST SEC_TYPE C0402
J 0
(-3525 -25);
DISPLAY 1.021277 (-3525 -25);
DISPLAY INVISIBLE (-3525 -25);
FORCEPROP 1 LAST PATH I7
J 0
(-3525 -75);
DISPLAY 0.978723 (-3525 -75);
PAINT WHITE (-3525 -75);
DISPLAY INVISIBLE (-3525 -75);
FORCEPROP 1 LAST LOCATION PC250
J 0
(-3525 -125);
DISPLAY 0.702128 (-3525 -125);
PAINT AQUA (-3525 -125);
FORCEPROP 1 LASTPIN (-3575 -125) $PN 1
J 0
(-3565 -145);
DISPLAY 0.808511 (-3565 -145);
PAINT WHITE (-3565 -145);
FORCEPROP 1 LASTPIN (-3575 -325) $PN 2
J 0
(-3565 -345);
DISPLAY 0.808511 (-3565 -345);
PAINT WHITE (-3565 -345);
FORCEPROP 2 LAST SEC 1
J 0
(-3525 -25);
DISPLAY 0.680851 (-3525 -25);
PAINT MONO (-3525 -25);
DISPLAY INVISIBLE (-3525 -25);
FORCEADD Q_RES..1
(1750 1325);
FORCEPROP 1 LAST PACK_TYPE 0402LF
J 0
(1675 1275);
DISPLAY 0.510638 (1675 1275);
PAINT SKYBLUE (1675 1275);
FORCEPROP 1 LAST PART_NUMBER CS00002JB13
J 0
(1650 1375);
DISPLAY 0.510638 (1650 1375);
PAINT WHITE (1650 1375);
FORCEPROP 1 LAST VALUE 0
J 2
(1975 1325);
DISPLAY 0.510638 (1975 1325);
PAINT SKYBLUE (1975 1325);
FORCEPROP 1 LAST MATERIAL EMPTY
J 0
(2000 1325);
DISPLAY 0.510638 (2000 1325);
PAINT RED (2000 1325);
FORCEPROP 2 LAST CDS_LIB pure_quanta
J 0
(1750 1325);
DISPLAY INVISIBLE (1750 1325);
FORCEPROP 1 LAST PATH I70
J 0
(1700 1475);
DISPLAY 0.978723 (1700 1475);
PAINT WHITE (1700 1475);
DISPLAY INVISIBLE (1700 1475);
FORCEPROP 1 LAST WATTAGE 1/16W
J 2
(1725 1175);
DISPLAY 0.510638 (1725 1175);
PAINT SKYBLUE (1725 1175);
DISPLAY INVISIBLE (1725 1175);
FORCEPROP 1 LAST TOLERANCE 5%
J 0
(1750 1225);
DISPLAY 0.510638 (1750 1225);
PAINT SKYBLUE (1750 1225);
DISPLAY INVISIBLE (1750 1225);
FORCEPROP 1 LAST $LOCATION R877
J 0
(1500 1325);
DISPLAY 0.702128 (1500 1325);
PAINT YELLOW (1500 1325);
FORCEPROP 1 LASTPIN (1650 1325) $PN 1
J 0
(1662 1337);
DISPLAY 0.787234 (1662 1337);
PAINT MONO (1662 1337);
FORCEPROP 1 LASTPIN (1850 1325) $PN 2
J 0
(1812 1337);
DISPLAY 0.787234 (1812 1337);
PAINT MONO (1812 1337);
FORCEPROP 0 LAST CDS_LOCATION R877
J 0
(1650 1400);
DISPLAY 0.680851 (1650 1400);
DISPLAY INVISIBLE (1650 1400);
FORCEPROP 0 LAST $SEC 1
J 0
(1650 1400);
DISPLAY 0.680851 (1650 1400);
PAINT MONO (1650 1400);
DISPLAY INVISIBLE (1650 1400);
FORCEPROP 0 LAST CDS_SEC 1
J 0
(1650 1400);
DISPLAY 0.680851 (1650 1400);
DISPLAY INVISIBLE (1650 1400);
FORCEADD OFFPAGE..5
R 2
(3025 1325);
FORCEPROP 2 LAST $XR0 56 
J 0
(3214 1325);
DISPLAY 0.638298 (3214 1325);
PAINT MONO (3214 1325);
FORCEPROP 2 LAST PATH I71
J 0
(3325 1375);
DISPLAY 0.680851 (3325 1375);
DISPLAY INVISIBLE (3325 1375);
FORCEPROP 2 LAST CDS_LIB standard
J 0
(3025 1325);
DISPLAY INVISIBLE (3025 1325);
FORCEPROP 1 LAST OFFPAGE TRUE
J 2
(2700 1200);
DISPLAY 0.872340 (2700 1200);
PAINT GREEN (2700 1200);
DISPLAY INVISIBLE (2700 1200);
FORCEPROP 1 LAST COMMENT_BODY TRUE
J 2
(2925 1250);
DISPLAY 0.872340 (2925 1250);
PAINT PEACH (2925 1250);
DISPLAY INVISIBLE (2925 1250);
FORCEADD UNIVERSAL_POWER..1
(-1700 3625);
FORCEPROP 3 LASTPIN (-1700 3575) SIG_NAME P3V3_LDO\g
J 0
(-1690 3585);
DISPLAY 0.659574 (-1690 3585);
PAINT MONO (-1690 3585);
DISPLAY INVISIBLE (-1690 3585);
FORCEPROP 1 LAST HDL_POWER P3V3_LDO
J 1
(-1700 3675);
DISPLAY 0.702128 (-1700 3675);
PAINT GREEN (-1700 3675);
FORCEPROP 1 LAST PATH I72
J 0
(-1650 3650);
DISPLAY 0.872340 (-1650 3650);
PAINT AQUA (-1650 3650);
DISPLAY INVISIBLE (-1650 3650);
FORCEPROP 2 LAST CDS_LIB logical_power
J 0
(-1700 3625);
DISPLAY INVISIBLE (-1700 3625);
FORCEADD Q_RES..2
(-3575 300);
FORCEPROP 1 LAST VALUE 5.1
J 0
(-3530 375);
DISPLAY 0.510638 (-3530 375);
PAINT SKYBLUE (-3530 375);
FORCEPROP 1 LAST TOLERANCE 5%
J 0
(-3530 325);
DISPLAY 0.510638 (-3530 325);
PAINT SKYBLUE (-3530 325);
FORCEPROP 1 LAST WATTAGE 1/16W
J 0
(-3535 275);
DISPLAY 0.510638 (-3535 275);
PAINT SKYBLUE (-3535 275);
FORCEPROP 1 LAST MATERIAL CHIP
J 0
(-3535 225);
DISPLAY 0.510638 (-3535 225);
PAINT SKYBLUE (-3535 225);
FORCEPROP 1 LAST PACK_TYPE 0402LF
J 0
(-3535 125);
DISPLAY 0.510638 (-3535 125);
PAINT SKYBLUE (-3535 125);
FORCEPROP 1 LAST PART_NUMBER CS-5102JB02
J 0
(-3535 175);
DISPLAY 0.510638 (-3535 175);
PAINT WHITE (-3535 175);
FORCEPROP 2 LAST CDS_LIB pure_quanta
J 0
(-3575 300);
DISPLAY INVISIBLE (-3575 300);
FORCEPROP 1 LAST PATH I8
J 0
(-3525 475);
DISPLAY 0.978723 (-3525 475);
PAINT WHITE (-3525 475);
DISPLAY INVISIBLE (-3525 475);
FORCEPROP 1 LAST LOCATION PR539
J 0
(-3530 425);
DISPLAY 0.702128 (-3530 425);
PAINT AQUA (-3530 425);
FORCEPROP 0 LAST $SEC 1
J 0
(-3525 475);
DISPLAY 0.680851 (-3525 475);
PAINT MONO (-3525 475);
DISPLAY INVISIBLE (-3525 475);
FORCEPROP 0 LAST CDS_SEC 1
J 0
(-3525 475);
DISPLAY 1.021277 (-3525 475);
DISPLAY INVISIBLE (-3525 475);
FORCEPROP 1 LASTPIN (-3575 400) $PN 1
J 0
(-3570 362);
DISPLAY 0.808511 (-3570 362);
PAINT WHITE (-3570 362);
DISPLAY INVISIBLE (-3570 362);
FORCEPROP 1 LASTPIN (-3575 200) $PN 2
J 0
(-3570 210);
DISPLAY 0.808511 (-3570 210);
PAINT WHITE (-3570 210);
DISPLAY INVISIBLE (-3570 210);
FORCEADD VCCAUX15..1
(-3575 500);
FORCEPROP 3 LASTPIN (-3575 450) SIG_NAME PVCC1_AUX\g
J 0
(-3565 460);
DISPLAY 0.659574 (-3565 460);
PAINT MONO (-3565 460);
DISPLAY INVISIBLE (-3565 460);
FORCEPROP 1 LAST HDL_POWER PVCC1_AUX
J 1
(-3575 550);
DISPLAY 0.702128 (-3575 550);
PAINT GREEN (-3575 550);
FORCEPROP 2 LAST CDS_LIB logical_power
J 0
(-3575 500);
DISPLAY INVISIBLE (-3575 500);
FORCEPROP 1 LAST PATH I9
J 0
(-3525 525);
DISPLAY 0.872340 (-3525 525);
PAINT AQUA (-3525 525);
DISPLAY INVISIBLE (-3525 525);
FORCEADD QUANTA_TITLE_BLOCK_C..1
(5300 -2175);
FORCEPROP 0 LAST CDS_CON_LAST_MODIFIED Fri Aug 25 17:25:49 2023
J 0
(3415 -2160);
DISPLAY INVISIBLE (3415 -2160);
FORCEPROP 2 LAST Q_DEPT 
J 1
(1537 -2126);
DISPLAY 1.957447 (1537 -2126);
PAINT GREEN (1537 -2126);
FORCEPROP 1 LAST CUSTOM_TXT_CDS <CON_LAST_MODIFIED>
J 0
(3415 -2160);
DISPLAY 0.978723 (3415 -2160);
FORCEPROP 2 LAST CUSTOM_TXT_CDS <XR_PAGE_TITLE>
J 0
(-2590 3075);
DISPLAY 0.638298 (-2590 3075);
PAINT PINK (-2590 3075);
DISPLAY INVISIBLE (-2590 3075);
FORCEPROP 1 LAST CUSTOM_TXT_CDS <NAME_2>
J 0
(2125 -2125);
FORCEPROP 1 LAST CUSTOM_TXT_CDS <NAME_1>
J 0
(2125 -2000);
FORCEPROP 1 LAST CUSTOM_TXT_CDS <Q_NUMBER>
J 0
(3897 -2072);
DISPLAY 1.212766 (3897 -2072);
FORCEPROP 1 LAST CUSTOM_TXT_CDS <Q_PROJ>
J 0
(2918 -2073);
DISPLAY 1.212766 (2918 -2073);
FORCEPROP 1 LAST CUSTOM_TXT_CDS <Q_REV>
J 0
(5116 -2072);
DISPLAY 1.212766 (5116 -2072);
FORCEPROP 1 LAST CUSTOM_TXT_CDS <CON_PAGE_NUM> OF <CON_TOTAL_PAGES>
J 0
(4854 -2157);
DISPLAY 0.978723 (4854 -2157);
FORCEPROP 1 LAST Q_TITLE NB695 - P1V2_AUX
J 0
(-4066 -2149);
DISPLAY 2.446809 (-4066 -2149);
PAINT GREEN (-4066 -2149);
FORCEPROP 2 LAST PAGE_BORDER TRUE
J 0
(-2590 3075);
DISPLAY 0.638298 (-2590 3075);
PAINT PINK (-2590 3075);
DISPLAY INVISIBLE (-2590 3075);
FORCEPROP 1 LAST CDS_LMAN_SYM_OUTLINE -9475,6775,100,-125
J 0
(5300 -2175);
DISPLAY 0.468085 (5300 -2175);
PAINT GREEN (5300 -2175);
DISPLAY INVISIBLE (5300 -2175);
FORCEPROP 2 LAST CDS_LIB pure_quanta
J 0
(5300 -2175);
DISPLAY INVISIBLE (5300 -2175);
FORCEPROP 1 LAST COMMENT_BODY TRUE
J 0
(5312 -2188);
DISPLAY 0.978723 (5312 -2188);
PAINT PEACH (5312 -2188);
DISPLAY INVISIBLE (5312 -2188);
FORCEPROP 2 LAST CDS_XR_PAGE_TITLE CR-55 : @SCM_LIB.SCM(SCH_1):PAGE55
J 0
(-2590 3075);
DISPLAY 0.638298 (-2590 3075);
PAINT PINK (-2590 3075);
DISPLAY INVISIBLE (-2590 3075);
FORCEADD DNS..2
(-1700 525);
PAINT RED (-1700 525);
FORCEPROP 2 LAST CDS_LIB mstr_misc
J 0
(-1700 525);
DISPLAY INVISIBLE (-1700 525);
FORCEPROP 1 LAST COMMENT_BODY TRUE
R 1
J 0
(-1625 300);
DISPLAY 0.872340 (-1625 300);
PAINT PEACH (-1625 300);
DISPLAY INVISIBLE (-1625 300);
FORCEADD DNS..2
(-1350 -1575);
PAINT RED (-1350 -1575);
FORCEPROP 2 LAST CDS_LIB mstr_misc
J 0
(-1350 -1575);
DISPLAY INVISIBLE (-1350 -1575);
FORCEPROP 1 LAST COMMENT_BODY TRUE
R 1
J 0
(-1275 -1800);
DISPLAY 0.872340 (-1275 -1800);
PAINT PEACH (-1275 -1800);
DISPLAY INVISIBLE (-1275 -1800);
FORCEADD CAD_NOTE..1
(1100 1650);
FORCEPROP 0 LAST L1 THE CAP & DAMPING RS FOR PWRGD SHOULD CLOSE TO DRIVE-END
J 0
(1050 1450);
DISPLAY 1.021277 (1050 1450);
PAINT WHITE (1050 1450);
FORCEPROP 1 LAST COMMENT_BODY TRUE
J 0
(1125 1750);
DISPLAY 0.978723 (1125 1750);
PAINT PEACH (1125 1750);
DISPLAY INVISIBLE (1125 1750);
FORCEPROP 2 LAST CDS_LIB logical_power
J 0
(1100 1650);
DISPLAY INVISIBLE (1100 1650);
FORCEADD DNS..2
(1300 900);
PAINT RED (1300 900);
FORCEPROP 1 LAST COMMENT_BODY TRUE
R 1
J 0
(1375 675);
DISPLAY 0.872340 (1375 675);
PAINT PEACH (1375 675);
DISPLAY INVISIBLE (1375 675);
FORCEPROP 2 LAST CDS_LIB mstr_misc
J 0
(1300 900);
DISPLAY INVISIBLE (1300 900);
FORCEADD DNS..2
(1725 1325);
PAINT RED (1725 1325);
FORCEPROP 2 LAST CDS_LIB mstr_misc
J 0
(1725 1325);
DISPLAY INVISIBLE (1725 1325);
FORCEPROP 1 LAST COMMENT_BODY TRUE
R 1
J 0
(1800 1100);
DISPLAY 0.872340 (1800 1100);
PAINT PEACH (1800 1100);
DISPLAY INVISIBLE (1800 1100);
WIRE 16 -1 (-1700 3525)(-1700 3575);
WIRE 16 -1 (-1700 3525)(-2050 3525);
WIRE 16 -1 (-3375 1550)(-3375 1850);
WIRE 16 -1 (-2875 1550)(-3375 1550);
WIRE 16 -1 (-3375 1475)(-3375 1550);
WIRE 16 -1 (-3575 450)(-3575 400);
WIRE 16 -1 (-625 -1550)(-625 -1450);
WIRE 16 -1 (-1250 -1550)(-625 -1550);
WIRE 16 -1 (-1900 -1500)(-1900 -1550);
WIRE 16 -1 (-625 -1225)(-625 -1125);
WIRE 16 -1 (-1250 -1225)(-625 -1225);
WIRE 16 -1 (-1900 -1150)(-1900 -1225);
WIRE 16 -1 (4575 575)(4575 650);
WIRE 16 -1 (4575 575)(3925 575);
WIRE 16 -1 (4575 575)(4575 -125);
WIRE 16 -1 (500 1450)(500 1575);
WIRE 16 -1 (-1700 3325)(-1700 3275);
WIRE 16 -1 (-2050 2700)(-2050 2575);
WIRE 16 -1 (-3375 1275)(-3375 1225);
WIRE 16 -1 (-2125 1075)(-2125 1025);
WIRE 16 -1 (-1725 1075)(-2125 1075);
WIRE 16 -1 (-2125 1200)(-2125 1075);
WIRE 16 -1 (-3575 -325)(-3575 -475);
WIRE 16 -1 (-1050 -800)(-1050 -700);
WIRE 16 -1 (3925 100)(3925 50);
WIRE 16 -1 (3925 225)(3925 100);
WIRE 16 -1 (3675 100)(3925 100);
WIRE 16 -1 (375 -275)(375 -475);
WIRE 16 -1 (375 -225)(375 -275);
WIRE 16 -1 (225 -275)(375 -275);
WIRE 16 -1 (-1225 -125)(-1225 -425);
WIRE 16 -1 (-575 -125)(-1225 -125);
WIRE 16 -1 (-1225 -125)(-1225 -25);
WIRE 16 -1 (1325 775)(1325 725);
WIRE 16 -1 (-1225 -25)(-575 -25);
WIRE 16 -1 (225 -225)(375 -225);
WIRE 16 -1 (-2850 2900)(-2300 2900);
FORCEPROP 0 LAST SIG_NAME PWRGD_P3V3_RGM
J 0
(-2885 2910);
DISPLAY 0.808511 (-2885 2910);
WIRE 16 -1 (1850 1325)(2975 1325);
FORCEPROP 2 LAST SIG_NAME PWRGD_P1V2_AUX_R2
J 2
(2790 1335);
DISPLAY 0.808511 (2790 1335);
WIRE 16 -1 (1850 1075)(2975 1075);
FORCEPROP 2 LAST SIG_NAME PWRGD_P1V2_AUX
J 2
(2790 1085);
DISPLAY 0.808511 (2790 1085);
WIRE 16 -1 (4575 -125)(225 -125);
WIRE 16 -1 (3925 575)(3925 425);
WIRE 16 -1 (3675 425)(3675 575);
WIRE 16 -1 (3675 575)(3925 575);
WIRE 16 -1 (3425 575)(3675 575);
WIRE 16 -1 (3425 425)(3425 575);
WIRE 16 -1 (3175 425)(3175 575);
WIRE 16 -1 (3175 575)(3425 575);
WIRE 16 -1 (2625 425)(2625 575);
WIRE 16 -1 (2625 575)(3175 575);
WIRE 16 -1 (2225 575)(2625 575);
WIRE 16 -1 (2625 225)(2625 100);
WIRE 16 -1 (2625 100)(3175 100);
WIRE 16 -1 (3175 225)(3175 100);
WIRE 16 -1 (3175 100)(3425 100);
WIRE 16 -1 (3425 225)(3425 100);
WIRE 16 -1 (3425 100)(3675 100);
WIRE 16 -1 (3675 225)(3675 100);
WIRE 16 -1 (-1225 375)(-575 375);
WIRE 16 -1 (-1225 75)(-1225 375);
WIRE 16 -1 (-575 75)(-1225 75);
WIRE 16 -1 (-3575 75)(-3575 -125);
WIRE 16 -1 (-3575 200)(-3575 75);
WIRE 16 -1 (-3575 75)(-1225 75);
FORCEPROP 2 LAST SIG_NAME P1V2_AUX_VCC
J 0
(-3210 85);
DISPLAY 0.808511 (-3210 85);
WIRE 16 -1 (-2625 475)(-1800 475);
FORCEPROP 2 LAST SIG_NAME PWRGD_P3V3_RGM_R3
J 0
(-2635 485);
DISPLAY 0.808511 (-2635 485);
WIRE 16 -1 (-2625 575)(-1800 575);
FORCEPROP 2 LAST SIG_NAME PWRGD_P1V8_AUX
J 0
(-2635 585);
DISPLAY 0.808511 (-2635 585);
WIRE 16 -1 (-2625 675)(-1800 675);
FORCEPROP 2 LAST SIG_NAME EN_P1V2_AUX
J 0
(-2635 685);
DISPLAY 0.808511 (-2635 685);
WIRE 16 -1 (-575 1075)(-725 1075);
WIRE 16 -1 (-725 1075)(-725 1550);
WIRE 16 -1 (-1175 1550)(-1175 1400);
WIRE 16 -1 (-725 1550)(-1175 1550);
WIRE 16 -1 (-1725 1400)(-1725 1550);
WIRE 16 -1 (-1725 1550)(-1175 1550);
WIRE 16 -1 (-2125 1400)(-2125 1550);
WIRE 16 -1 (-1725 1550)(-2125 1550);
WIRE 16 -1 (-2675 1550)(-2125 1550);
FORCEPROP 2 LAST SIG_NAME SW_P1V2_AUX_FLT
J 0
(-2485 1560);
DISPLAY 0.808511 (-2485 1560);
WIRE 16 -1 (-2050 3200)(-2050 3525);
WIRE 16 -1 (-2850 3000)(-2300 3000);
FORCEPROP 0 LAST SIG_NAME PWRGD_P5V_AUX
J 0
(-2885 3010);
DISPLAY 0.808511 (-2885 3010);
WIRE 16 -1 (-825 2950)(-1700 2950);
FORCEPROP 2 LAST SIG_NAME EN_P1V2_AUX
J 0
(-1335 2960);
DISPLAY 0.808511 (-1335 2960);
WIRE 16 -1 (-1600 475)(-1250 475);
WIRE 16 -1 (-1250 475)(-1250 575);
WIRE 16 -1 (-575 575)(-1250 575);
FORCEPROP 2 LAST SIG_NAME EN_P1V2_AUX_R
J 0
(-1210 585);
DISPLAY 0.808511 (-1210 585);
WIRE 16 -1 (-1600 575)(-1250 575);
WIRE 16 -1 (-1250 575)(-1250 675);
WIRE 16 -1 (-1600 675)(-1250 675);
WIRE 16 -1 (225 575)(875 575);
FORCEPROP 2 LAST SIG_NAME SW_P1V2_AUX_SW
J 0
(315 585);
DISPLAY 0.808511 (315 585);
WIRE 16 -1 (875 575)(2025 575);
WIRE 16 -1 (875 625)(875 575);
WIRE 16 -1 (1650 1325)(1325 1325);
WIRE 16 -1 (1325 1075)(1325 975);
WIRE 16 -1 (1325 1325)(1325 1075);
WIRE 16 -1 (1650 1075)(1325 1075);
WIRE 16 -1 (500 1250)(500 1075);
WIRE 16 -1 (500 1075)(1325 1075);
FORCEPROP 2 LAST SIG_NAME PWRGD_P1V2_AUX_R
J 2
(1290 1085);
DISPLAY 0.808511 (1290 1085);
WIRE 16 -1 (225 1075)(500 1075);
WIRE 16 -1 (-1175 1200)(-1175 1075);
WIRE 16 -1 (-1725 1200)(-1725 1075);
WIRE 16 -1 (-1175 1075)(-1725 1075);
WIRE 16 -1 (-1900 -1225)(-1450 -1225);
WIRE 16 -1 (-1900 -1550)(-1450 -1550);
WIRE 16 -1 (225 875)(875 875);
FORCEPROP 2 LAST SIG_NAME SW_P1V2_AUX_BST
J 0
(315 885);
DISPLAY 0.808511 (315 885);
WIRE 16 -1 (875 825)(875 875);
WIRE 16 2175 (-3675 -825)(-2550 -825);
WIRE 16 2175 (-2550 -825)(-2550 -1200);
WIRE 16 2175 (-3675 -825)(-3675 -1200);
WIRE 16 2175 (-3675 -1200)(-2550 -1200);
WIRE 16 2175 (-3675 -1625)(-2550 -1625);
WIRE 16 2175 (-2550 -1250)(-2550 -1625);
WIRE 16 2175 (-3675 -1250)(-3675 -1625);
WIRE 16 2175 (-3675 -1250)(-2550 -1250);
WIRE 16 2175 (3238 3856)(4916 3856);
WIRE 16 2175 (4916 3856)(4916 2965);
WIRE 16 2175 (3238 3856)(3238 2965);
WIRE 16 2175 (3238 2965)(4916 2965);
WIRE 16 -1 (-1050 -275)(-1050 -500);
WIRE 16 -1 (-575 -275)(-1050 -275);
FORCEPROP 2 LAST SIG_NAME P1V2_AUX_MODE
J 0
(-1135 -265);
DISPLAY 0.808511 (-1135 -265);
DOT 1 (875 575);
DOT 1 (-1250 575);
DOT 1 (-1725 1075);
DOT 1 (1325 1075);
DOT 1 (-1175 1550);
DOT 1 (-3375 1550);
DOT 1 (4575 575);
DOT 1 (-1725 1550);
DOT 1 (3925 575);
DOT 1 (3675 575);
DOT 1 (3925 100);
DOT 1 (3425 575);
DOT 1 (3175 575);
DOT 1 (2625 575);
DOT 1 (3425 100);
DOT 1 (3175 100);
DOT 1 (-2125 1550);
DOT 1 (500 1075);
DOT 1 (-2125 1075);
DOT 1 (375 -275);
DOT 1 (3675 100);
DOT 1 (-3575 75);
DOT 1 (-1225 75);
DOT 1 (-1225 -125);
FORCENOTE
P1V2_AUX
(-825 2175) 0;
DISPLAY LEFT (-825 2175);
DISPLAY 3.148936 (-825 2175);
FORCENOTE
DESIGN SPECIFICATION
(3275 3775) 0;
DISPLAY LEFT (3275 3775);
DISPLAY 1.170213 (3275 3775);
FORCENOTE
OUTPUT VOLTAGE=1.2V
(3275 3675) 0;
DISPLAY LEFT (3275 3675);
DISPLAY 1.042553 (3275 3675);
FORCENOTE
OUTPUT RIPPLE=+/-1%
(3275 3600) 0;
DISPLAY LEFT (3275 3600);
DISPLAY 0.936170 (3275 3600);
FORCENOTE
TRANSIENT TOLERANCE=+/-5%
(3275 3525) 0;
DISPLAY LEFT (3275 3525);
DISPLAY 0.936170 (3275 3525);
FORCENOTE
MAX CURRENT=0.87A
(3275 3375) 0;
DISPLAY LEFT (3275 3375);
DISPLAY 0.936170 (3275 3375);
FORCENOTE
TDC=0.73A
(3275 3450) 0;
DISPLAY LEFT (3275 3450);
DISPLAY 0.936170 (3275 3450);
FORCENOTE
2ND AL051372000
(-3575 -1125) 0;
DISPLAY LEFT (-3575 -1125);
DISPLAY 1.170213 (-3575 -1125);
FORCENOTE
1ST AL000695001
(-3575 -1025) 0;
DISPLAY LEFT (-3575 -1025);
DISPLAY 1.170213 (-3575 -1025);
FORCENOTE
IC TABLE
(-3575 -925) 0;
DISPLAY LEFT (-3575 -925);
DISPLAY 1.170213 (-3575 -925);
FORCENOTE
R TABLE
(-3575 -1350) 0;
DISPLAY LEFT (-3575 -1350);
DISPLAY 1.170213 (-3575 -1350);
FORCENOTE
1ST MPS USE 3V3
(-3575 -1450) 0;
DISPLAY LEFT (-3575 -1450);
DISPLAY 1.170213 (-3575 -1450);
FORCENOTE
WORK FREQUENCY=750KHZ
(3275 3075) 0;
DISPLAY LEFT (3275 3075);
DISPLAY 0.936170 (3275 3075);
FORCENOTE
SLEW RATE=0.25A/US
(3275 3150) 0;
DISPLAY LEFT (3275 3150);
DISPLAY 0.936170 (3275 3150);
FORCENOTE
CURRENT STEP=0.7A
(3275 3225) 0;
DISPLAY LEFT (3275 3225);
DISPLAY 0.936170 (3275 3225);
FORCENOTE
OVER CURRENT PROTECTION(IC RATING)=4A
(3275 3300) 0;
DISPLAY LEFT (3275 3300);
DISPLAY 0.936170 (3275 3300);
FORCENOTE
2ND TI USE 5V
(-3575 -1550) 0;
DISPLAY LEFT (-3575 -1550);
DISPLAY 1.170213 (-3575 -1550);
QUIT
